G04*
G04 #@! TF.GenerationSoftware,Altium Limited,Altium Designer,22.4.2 (48)*
G04*
G04 Layer_Color=7949734*
%FSLAX25Y25*%
%MOIN*%
G70*
G04*
G04 #@! TF.SameCoordinates,B69760C6-9901-4916-8BAC-4CFDAA04743E*
G04*
G04*
G04 #@! TF.FilePolarity,Positive*
G04*
G01*
G75*
%ADD56C,0.00600*%
G36*
X28822Y96912D02*
X28833D01*
Y96866D01*
X28845D01*
Y96854D01*
X28856D01*
Y96842D01*
X28833D01*
Y96773D01*
X28822D01*
Y96762D01*
X28810D01*
Y96716D01*
X28822D01*
Y96704D01*
X28833D01*
Y96739D01*
X28845D01*
Y96635D01*
X28868D01*
Y96658D01*
X28879D01*
Y96681D01*
X28914D01*
Y96704D01*
X28925D01*
Y96716D01*
X28937D01*
Y96670D01*
X28948D01*
Y96635D01*
X28937D01*
Y96555D01*
X28948D01*
Y96497D01*
X28960D01*
Y96486D01*
X28948D01*
Y96474D01*
X28937D01*
Y96463D01*
X28960D01*
Y96451D01*
X28971D01*
Y96405D01*
X28983D01*
Y96359D01*
X28971D01*
Y96336D01*
X28983D01*
Y96313D01*
X28971D01*
Y96278D01*
X28983D01*
Y96186D01*
X28971D01*
Y96152D01*
X28983D01*
Y96094D01*
X28994D01*
Y96105D01*
X29006D01*
Y96117D01*
X29017D01*
Y96071D01*
X29006D01*
Y96059D01*
X28994D01*
Y96025D01*
X29017D01*
Y96013D01*
X29029D01*
Y95967D01*
X29017D01*
Y95944D01*
X29029D01*
Y95852D01*
X29041D01*
Y95749D01*
X29052D01*
Y95737D01*
X29063D01*
Y95714D01*
X29052D01*
Y95691D01*
X29041D01*
Y95599D01*
X29052D01*
Y95587D01*
X29063D01*
Y95541D01*
X29075D01*
Y95507D01*
X29087D01*
Y95415D01*
X29098D01*
Y95403D01*
X29110D01*
Y95380D01*
X29098D01*
Y95357D01*
X29087D01*
Y95345D01*
X29075D01*
Y95322D01*
X29087D01*
Y95265D01*
X29098D01*
Y95253D01*
X29110D01*
Y95219D01*
X29098D01*
Y95207D01*
X29087D01*
Y95184D01*
X29110D01*
Y95196D01*
X29121D01*
Y95161D01*
X29133D01*
Y95081D01*
X29144D01*
Y95046D01*
X29156D01*
Y94977D01*
X29144D01*
Y94954D01*
X29167D01*
Y94942D01*
X29144D01*
Y94931D01*
X29133D01*
Y94908D01*
X29144D01*
Y94896D01*
X29156D01*
Y94839D01*
X29144D01*
Y94827D01*
X29110D01*
Y94816D01*
X29156D01*
Y94804D01*
X29190D01*
Y94735D01*
X29179D01*
Y94747D01*
X29167D01*
Y94770D01*
X29156D01*
Y94781D01*
X29144D01*
Y94793D01*
X29121D01*
Y94712D01*
X29133D01*
Y94666D01*
X29144D01*
Y94643D01*
X29156D01*
Y94631D01*
X29167D01*
Y94597D01*
X29179D01*
Y94539D01*
X29190D01*
Y94551D01*
X29202D01*
Y94608D01*
X29213D01*
Y94505D01*
X29202D01*
Y94482D01*
X29236D01*
Y94401D01*
X29225D01*
Y94378D01*
X29248D01*
Y94401D01*
X29259D01*
Y94297D01*
X29271D01*
Y94159D01*
X29259D01*
Y94217D01*
X29248D01*
Y94228D01*
X29225D01*
Y94251D01*
X29236D01*
Y94263D01*
X29225D01*
Y94286D01*
X29213D01*
Y94274D01*
X29202D01*
Y94309D01*
X29213D01*
Y94332D01*
X29202D01*
Y94389D01*
X29190D01*
Y94401D01*
X29179D01*
Y94436D01*
X29167D01*
Y94355D01*
X29179D01*
Y94274D01*
X29190D01*
Y94251D01*
X29202D01*
Y94171D01*
X29213D01*
Y94090D01*
X29236D01*
Y94102D01*
X29248D01*
Y94113D01*
X29259D01*
Y94067D01*
X29248D01*
Y94044D01*
X29236D01*
Y94021D01*
X29225D01*
Y93998D01*
X29248D01*
Y94010D01*
X29259D01*
Y94033D01*
X29271D01*
Y93963D01*
X29282D01*
Y93952D01*
X29294D01*
Y93940D01*
X29305D01*
Y93860D01*
X29317D01*
Y93814D01*
X29294D01*
Y93825D01*
X29305D01*
Y93837D01*
X29294D01*
Y93871D01*
X29271D01*
Y93860D01*
X29259D01*
Y93883D01*
X29271D01*
Y93952D01*
X29248D01*
Y93975D01*
X29225D01*
Y93940D01*
X29236D01*
Y93917D01*
X29248D01*
Y93906D01*
X29236D01*
Y93894D01*
X29248D01*
Y93860D01*
X29236D01*
Y93837D01*
X29248D01*
Y93791D01*
X29271D01*
Y93733D01*
X29259D01*
Y93722D01*
X29271D01*
Y93699D01*
X29282D01*
Y93641D01*
X29271D01*
Y93629D01*
X29282D01*
Y93618D01*
X29294D01*
Y93606D01*
X29317D01*
Y93618D01*
X29328D01*
Y93629D01*
X29340D01*
Y93641D01*
X29363D01*
Y93652D01*
X29375D01*
Y93629D01*
X29363D01*
Y93595D01*
X29340D01*
Y93583D01*
X29328D01*
Y93560D01*
X29317D01*
Y93549D01*
X29328D01*
Y93526D01*
X29340D01*
Y93491D01*
X29351D01*
Y93503D01*
X29363D01*
Y93526D01*
X29351D01*
Y93549D01*
X29375D01*
Y93560D01*
X29386D01*
Y93572D01*
X29397D01*
Y93549D01*
X29409D01*
Y93583D01*
X29397D01*
Y93595D01*
X29409D01*
Y93606D01*
X29432D01*
Y93629D01*
X29455D01*
Y93641D01*
X29467D01*
Y93664D01*
X29478D01*
Y93676D01*
X29490D01*
Y93687D01*
X29501D01*
Y93699D01*
X29524D01*
Y93710D01*
X29536D01*
Y93722D01*
X29547D01*
Y93733D01*
X29536D01*
Y93745D01*
X29547D01*
Y93779D01*
X29559D01*
Y93791D01*
X29570D01*
Y93802D01*
X29582D01*
Y93825D01*
X29593D01*
Y93814D01*
X29616D01*
Y93825D01*
X29628D01*
Y93837D01*
X29651D01*
Y93848D01*
X29662D01*
Y93860D01*
X29674D01*
Y93871D01*
X29662D01*
Y93883D01*
X29651D01*
Y93906D01*
X29639D01*
Y93917D01*
X29662D01*
Y93952D01*
X29674D01*
Y93963D01*
X29685D01*
Y93975D01*
X29697D01*
Y93952D01*
X29720D01*
Y93963D01*
X29732D01*
Y93975D01*
X29743D01*
Y93986D01*
X29754D01*
Y93998D01*
X29766D01*
Y94010D01*
X29778D01*
Y94033D01*
X29789D01*
Y94044D01*
X29801D01*
Y94055D01*
X29812D01*
Y94067D01*
X29835D01*
Y94079D01*
X29847D01*
Y94090D01*
X29858D01*
Y94102D01*
X29881D01*
Y94090D01*
X29904D01*
Y94102D01*
X29950D01*
Y94113D01*
X29973D01*
Y94136D01*
X29962D01*
Y94148D01*
X29973D01*
Y94159D01*
X29962D01*
Y94182D01*
X29973D01*
Y94205D01*
X29950D01*
Y94217D01*
X29996D01*
Y94205D01*
X30008D01*
Y94217D01*
X30019D01*
Y94240D01*
X30031D01*
Y94263D01*
X30042D01*
Y94274D01*
X30065D01*
Y94286D01*
X30077D01*
Y94297D01*
X30088D01*
Y94320D01*
X30100D01*
Y94355D01*
X30112D01*
Y94343D01*
X30123D01*
Y94355D01*
X30112D01*
Y94436D01*
X30123D01*
Y94447D01*
X30146D01*
Y94424D01*
X30135D01*
Y94412D01*
X30123D01*
Y94378D01*
Y94367D01*
Y94355D01*
X30135D01*
Y94367D01*
X30146D01*
Y94378D01*
X30158D01*
Y94401D01*
X30181D01*
Y94412D01*
X30192D01*
Y94447D01*
X30204D01*
Y94459D01*
X30215D01*
Y94470D01*
X30227D01*
Y94482D01*
X30238D01*
Y94493D01*
X30250D01*
Y94505D01*
X30261D01*
Y94516D01*
X30273D01*
Y94528D01*
X30284D01*
Y94551D01*
X30296D01*
Y94574D01*
X30319D01*
Y94585D01*
X30330D01*
Y94597D01*
X30342D01*
Y94620D01*
X30353D01*
Y94643D01*
X30365D01*
Y94666D01*
X30353D01*
Y94654D01*
X30342D01*
Y94677D01*
X30376D01*
Y94689D01*
X30388D01*
Y94677D01*
X30399D01*
Y94689D01*
X30411D01*
Y94700D01*
X30422D01*
Y94712D01*
X30434D01*
Y94723D01*
X30457D01*
Y94735D01*
X30468D01*
Y94758D01*
X30480D01*
Y94770D01*
X30492D01*
Y94781D01*
X30515D01*
Y94793D01*
X30526D01*
Y94816D01*
X30549D01*
Y94827D01*
X30561D01*
Y94850D01*
X30572D01*
Y94873D01*
X30595D01*
Y94885D01*
X30607D01*
Y94908D01*
X30630D01*
Y94931D01*
X30641D01*
Y94942D01*
X30653D01*
Y94954D01*
X30676D01*
Y94965D01*
X30687D01*
Y94977D01*
X30699D01*
Y94988D01*
X30733D01*
Y94977D01*
X30745D01*
Y94965D01*
X30756D01*
Y94977D01*
X30768D01*
Y94862D01*
X30756D01*
Y94850D01*
X30768D01*
Y94839D01*
X30779D01*
Y94827D01*
X30768D01*
Y94804D01*
X30779D01*
Y94781D01*
X30768D01*
Y94770D01*
X30803D01*
Y94793D01*
X30791D01*
Y94816D01*
X30803D01*
Y94839D01*
X30814D01*
Y94781D01*
X30825D01*
Y94793D01*
X30837D01*
Y94770D01*
X30825D01*
Y94723D01*
X30860D01*
Y94689D01*
X30872D01*
Y94631D01*
X30860D01*
Y94574D01*
X30849D01*
Y94482D01*
X30825D01*
Y94343D01*
X30814D01*
Y94320D01*
X30803D01*
Y94297D01*
X30814D01*
Y94274D01*
X30803D01*
Y94240D01*
X30791D01*
Y94228D01*
X30779D01*
Y94194D01*
X30791D01*
Y94182D01*
X30779D01*
Y94171D01*
X30768D01*
Y94136D01*
X30756D01*
Y94102D01*
X30745D01*
Y94079D01*
X30733D01*
Y94044D01*
X30722D01*
Y93998D01*
X30710D01*
Y93975D01*
Y93963D01*
X30699D01*
Y93952D01*
X30710D01*
Y93940D01*
X30699D01*
Y93929D01*
X30687D01*
Y93883D01*
X30676D01*
Y93814D01*
X30664D01*
Y93802D01*
X30653D01*
Y93791D01*
X30664D01*
Y93779D01*
X30653D01*
Y93756D01*
X30641D01*
Y93733D01*
X30630D01*
Y93722D01*
X30641D01*
Y93699D01*
X30630D01*
Y93664D01*
X30618D01*
Y93641D01*
X30607D01*
Y93618D01*
X30595D01*
Y93572D01*
X30584D01*
Y93583D01*
X30572D01*
Y93560D01*
X30584D01*
Y93537D01*
X30618D01*
Y93526D01*
X30607D01*
Y93514D01*
X30595D01*
Y93526D01*
X30584D01*
Y93537D01*
X30572D01*
Y93514D01*
X30584D01*
Y93503D01*
X30595D01*
Y93445D01*
X30584D01*
Y93491D01*
X30572D01*
Y93503D01*
X30549D01*
Y93480D01*
X30561D01*
Y93468D01*
X30572D01*
Y93445D01*
X30584D01*
Y93434D01*
X30595D01*
Y93411D01*
X30584D01*
Y93388D01*
X30561D01*
Y93365D01*
X30572D01*
Y93353D01*
X30584D01*
Y93318D01*
X30561D01*
Y93330D01*
X30538D01*
Y93318D01*
X30549D01*
Y93295D01*
X30561D01*
Y93284D01*
X30572D01*
Y93238D01*
X30561D01*
Y93226D01*
X30549D01*
Y93169D01*
X30538D01*
Y93111D01*
X30526D01*
Y93088D01*
X30515D01*
Y93077D01*
X30503D01*
Y93065D01*
X30492D01*
Y93077D01*
X30480D01*
Y93031D01*
X30492D01*
Y93054D01*
X30503D01*
Y93019D01*
X30480D01*
Y92996D01*
X30492D01*
Y92984D01*
X30480D01*
Y92973D01*
X30468D01*
Y92962D01*
X30457D01*
Y92904D01*
X30446D01*
Y92881D01*
X30434D01*
Y92823D01*
X30422D01*
Y92812D01*
X30411D01*
Y92766D01*
X30399D01*
Y92754D01*
X30388D01*
Y92731D01*
X30376D01*
Y92720D01*
X30365D01*
Y92662D01*
X30353D01*
Y92651D01*
X30342D01*
Y92604D01*
X30330D01*
Y92593D01*
X30319D01*
Y92535D01*
X30307D01*
Y92478D01*
X30296D01*
Y92466D01*
X30307D01*
Y92443D01*
X30296D01*
Y92328D01*
X30284D01*
Y92305D01*
X30273D01*
Y92282D01*
X30261D01*
Y92270D01*
X30250D01*
Y92247D01*
X30261D01*
Y92236D01*
X30250D01*
Y92190D01*
X30261D01*
Y92213D01*
X30273D01*
Y92201D01*
X30284D01*
Y92178D01*
X30273D01*
Y92167D01*
X30261D01*
Y92132D01*
X30250D01*
Y92098D01*
X30215D01*
Y92086D01*
X30227D01*
Y92063D01*
X30238D01*
Y92052D01*
X30227D01*
Y92040D01*
X30215D01*
Y92029D01*
X30204D01*
Y91983D01*
X30192D01*
Y91948D01*
X30204D01*
Y91936D01*
X30192D01*
Y91902D01*
X30181D01*
Y91867D01*
X30169D01*
Y91833D01*
X30158D01*
Y91798D01*
X30146D01*
Y91764D01*
X30135D01*
Y91752D01*
X30146D01*
Y91741D01*
X30135D01*
Y91729D01*
X30123D01*
Y91706D01*
X30112D01*
Y91649D01*
X30100D01*
Y91602D01*
X30088D01*
Y91580D01*
X30100D01*
Y91545D01*
X30088D01*
Y91533D01*
X30077D01*
Y91499D01*
X30065D01*
Y91453D01*
X30054D01*
Y91418D01*
X30042D01*
Y91407D01*
X30019D01*
Y91384D01*
X30031D01*
Y91372D01*
X30008D01*
Y91338D01*
X30019D01*
Y91315D01*
X30008D01*
Y91303D01*
X29996D01*
Y91257D01*
X29950D01*
Y91246D01*
X29939D01*
Y91211D01*
X29927D01*
Y91176D01*
X29916D01*
Y91142D01*
X29904D01*
Y91130D01*
X29893D01*
Y91096D01*
X29881D01*
Y91084D01*
X29904D01*
Y91061D01*
X29881D01*
Y91050D01*
X29904D01*
Y91038D01*
X29870D01*
Y91050D01*
X29858D01*
Y91038D01*
X29847D01*
Y91027D01*
X29858D01*
Y91004D01*
X29904D01*
Y91015D01*
X29996D01*
Y91004D01*
X29939D01*
Y90958D01*
X29904D01*
Y90946D01*
X29858D01*
Y90935D01*
X29835D01*
Y90923D01*
X29824D01*
Y90865D01*
X29950D01*
Y90877D01*
X30031D01*
Y90889D01*
X30042D01*
Y90900D01*
X30054D01*
Y90889D01*
X30077D01*
Y90877D01*
X30135D01*
Y90889D01*
X30146D01*
Y90900D01*
X30158D01*
Y90912D01*
X30169D01*
Y90900D01*
X30204D01*
Y90889D01*
X30215D01*
Y90865D01*
X30261D01*
Y90854D01*
X30284D01*
Y90865D01*
X30353D01*
Y90831D01*
X30342D01*
Y90819D01*
X30399D01*
Y90842D01*
X30388D01*
Y90854D01*
X30376D01*
Y90865D01*
X30446D01*
Y90877D01*
X30468D01*
Y90889D01*
X30503D01*
Y90877D01*
X30572D01*
Y90865D01*
X30618D01*
Y90900D01*
X30607D01*
Y90889D01*
X30584D01*
Y90900D01*
X30515D01*
Y90912D01*
X30457D01*
Y90900D01*
X30446D01*
Y90889D01*
X30434D01*
Y90900D01*
X30399D01*
Y90912D01*
X30388D01*
Y90923D01*
X30399D01*
Y90946D01*
X30365D01*
Y90935D01*
X30284D01*
Y90958D01*
X30307D01*
Y90969D01*
X30319D01*
Y90958D01*
X30342D01*
Y90969D01*
X30457D01*
Y90981D01*
X30468D01*
Y90992D01*
X30480D01*
Y91004D01*
X30503D01*
Y90992D01*
X30538D01*
Y91004D01*
X30687D01*
Y91015D01*
X30710D01*
Y91004D01*
X30722D01*
Y91027D01*
X30745D01*
Y91038D01*
X30803D01*
Y91050D01*
X31021D01*
Y91061D01*
X31148D01*
Y91050D01*
X31171D01*
Y91073D01*
X31183D01*
Y91084D01*
X31309D01*
Y91096D01*
X31390D01*
Y91107D01*
X31413D01*
Y91096D01*
X31471D01*
Y91107D01*
X31482D01*
Y91096D01*
X31517D01*
Y91084D01*
X31540D01*
Y91073D01*
X31563D01*
Y91061D01*
X31586D01*
Y91073D01*
X31597D01*
Y91084D01*
X31609D01*
Y91073D01*
X31620D01*
Y91061D01*
X31793D01*
Y91050D01*
X31839D01*
Y91038D01*
X31862D01*
Y91027D01*
X31874D01*
Y91015D01*
X31897D01*
Y91004D01*
X32012D01*
Y91027D01*
X32000D01*
Y91038D01*
X32012D01*
Y91027D01*
X32035D01*
Y91004D01*
X32081D01*
Y91015D01*
X32173D01*
Y91027D01*
X32208D01*
Y91004D01*
X32231D01*
Y91038D01*
X32265D01*
Y91050D01*
X32173D01*
Y91061D01*
X32184D01*
Y91073D01*
X32138D01*
Y91084D01*
X32150D01*
Y91096D01*
X32162D01*
Y91107D01*
X32173D01*
Y91119D01*
X32184D01*
Y91142D01*
X32081D01*
Y91130D01*
X32046D01*
Y91142D01*
X32000D01*
Y91130D01*
X31989D01*
Y91142D01*
X31977D01*
Y91130D01*
X31931D01*
Y91142D01*
X31920D01*
Y91153D01*
X32035D01*
Y91165D01*
X32046D01*
Y91176D01*
X32081D01*
Y91165D01*
X32104D01*
Y91176D01*
X32115D01*
Y91188D01*
X32208D01*
Y91176D01*
X32184D01*
Y91153D01*
X32196D01*
Y91130D01*
X32208D01*
Y91119D01*
X32231D01*
Y91130D01*
X32265D01*
Y91119D01*
X32277D01*
Y91130D01*
X32300D01*
Y91142D01*
X32323D01*
Y91153D01*
X32346D01*
Y91176D01*
X32334D01*
Y91188D01*
X32323D01*
Y91199D01*
X32346D01*
Y91223D01*
X32334D01*
Y91234D01*
X32380D01*
Y91246D01*
X32403D01*
Y91234D01*
X32415D01*
Y91211D01*
X32426D01*
Y91199D01*
X32415D01*
Y91188D01*
X32403D01*
Y91176D01*
X32392D01*
Y91165D01*
X32380D01*
Y91153D01*
X32369D01*
Y91142D01*
X32415D01*
Y91153D01*
X32461D01*
Y91165D01*
X32553D01*
Y91176D01*
X32564D01*
Y91188D01*
X32611D01*
Y91165D01*
X32599D01*
Y91142D01*
X32622D01*
Y91153D01*
X32634D01*
Y91176D01*
X32657D01*
Y91188D01*
X32668D01*
Y91199D01*
X32680D01*
Y91223D01*
X32691D01*
Y91211D01*
X32714D01*
Y91142D01*
X32703D01*
Y91107D01*
X32691D01*
Y91096D01*
X32680D01*
Y91073D01*
X32703D01*
Y91050D01*
X32714D01*
Y91027D01*
X32726D01*
Y90981D01*
X32714D01*
Y90923D01*
X32668D01*
Y90912D01*
X32657D01*
Y90865D01*
X32622D01*
Y90854D01*
X32611D01*
Y90842D01*
X32599D01*
Y90819D01*
X32611D01*
Y90808D01*
X32645D01*
Y90819D01*
X32668D01*
Y90831D01*
X32680D01*
Y90865D01*
X32691D01*
Y90877D01*
X32726D01*
Y90831D01*
X32714D01*
Y90808D01*
X32680D01*
Y90796D01*
X32691D01*
Y90785D01*
X32703D01*
Y90773D01*
X32691D01*
Y90762D01*
X32668D01*
Y90739D01*
X32657D01*
Y90727D01*
X32645D01*
Y90716D01*
X32622D01*
Y90704D01*
X32634D01*
Y90693D01*
X32645D01*
Y90670D01*
X32622D01*
Y90658D01*
X32611D01*
Y90635D01*
X32622D01*
Y90624D01*
X32611D01*
Y90612D01*
X32599D01*
Y90601D01*
X32588D01*
Y90589D01*
X32576D01*
Y90578D01*
X32611D01*
Y90554D01*
X32599D01*
Y90543D01*
X32588D01*
Y90531D01*
X32576D01*
Y90520D01*
X32553D01*
Y90508D01*
X32541D01*
Y90485D01*
X32553D01*
Y90474D01*
X32541D01*
Y90485D01*
X32507D01*
Y90474D01*
X32530D01*
Y90462D01*
X32519D01*
Y90451D01*
X32507D01*
Y90439D01*
X32495D01*
Y90405D01*
X32484D01*
Y90393D01*
X32472D01*
Y90382D01*
X32461D01*
Y90370D01*
X32472D01*
Y90359D01*
X32484D01*
Y90370D01*
X32507D01*
Y90359D01*
X32495D01*
Y90347D01*
X32461D01*
Y90324D01*
X32426D01*
Y90313D01*
X32449D01*
Y90301D01*
X32461D01*
Y90290D01*
X32484D01*
Y90278D01*
X32438D01*
Y90267D01*
X32426D01*
Y90244D01*
X32403D01*
Y90267D01*
X32380D01*
Y90255D01*
X32357D01*
Y90232D01*
X32369D01*
Y90244D01*
X32392D01*
Y90220D01*
X32380D01*
Y90209D01*
X32357D01*
Y90232D01*
X32346D01*
Y90209D01*
X32357D01*
Y90186D01*
X32346D01*
Y90163D01*
X32369D01*
Y90151D01*
X32380D01*
Y90163D01*
X32369D01*
Y90175D01*
X32415D01*
Y90163D01*
X32426D01*
Y90151D01*
X32415D01*
Y90140D01*
X32403D01*
Y90128D01*
X32392D01*
Y90117D01*
X32380D01*
Y90128D01*
X32369D01*
Y90117D01*
X32380D01*
Y90105D01*
X32369D01*
Y90071D01*
X32392D01*
Y90059D01*
X32380D01*
Y90048D01*
X32369D01*
Y90059D01*
X32334D01*
Y90048D01*
X32323D01*
Y90036D01*
X32311D01*
Y90013D01*
X32323D01*
Y90002D01*
X32277D01*
Y89967D01*
X32254D01*
Y89933D01*
X32242D01*
Y89921D01*
X32231D01*
Y89910D01*
X32219D01*
Y89898D01*
X32208D01*
Y89886D01*
X32196D01*
Y89875D01*
X32184D01*
Y89864D01*
X32173D01*
Y89852D01*
X32162D01*
Y89841D01*
X32150D01*
Y89829D01*
X32127D01*
Y89806D01*
X32115D01*
Y89794D01*
X32104D01*
Y89783D01*
X32092D01*
Y89771D01*
X32081D01*
Y89748D01*
X32069D01*
Y89725D01*
X32058D01*
Y89702D01*
X32046D01*
Y89679D01*
X32035D01*
Y89656D01*
X32023D01*
Y89645D01*
X32012D01*
Y89633D01*
X32000D01*
Y89599D01*
X31989D01*
Y89576D01*
X31977D01*
Y89564D01*
X31966D01*
Y89553D01*
X31954D01*
Y89530D01*
X31943D01*
Y89483D01*
X31931D01*
Y89472D01*
X31920D01*
Y89460D01*
X31908D01*
Y89414D01*
X31897D01*
Y89403D01*
X31885D01*
Y89391D01*
X31874D01*
Y89380D01*
X31862D01*
Y89345D01*
X31850D01*
Y89299D01*
X31839D01*
Y89288D01*
X31828D01*
Y89265D01*
X31804D01*
Y89242D01*
X31793D01*
Y89207D01*
X31781D01*
Y89196D01*
X31770D01*
Y89173D01*
X31758D01*
Y89161D01*
X31747D01*
Y89138D01*
X31735D01*
Y89126D01*
X31724D01*
Y89115D01*
X31701D01*
Y89080D01*
X31689D01*
Y89069D01*
X31678D01*
Y89046D01*
X31666D01*
Y89023D01*
X31678D01*
Y89011D01*
X31655D01*
Y88988D01*
X31666D01*
Y88965D01*
X31655D01*
Y88977D01*
X31643D01*
Y88954D01*
X31655D01*
Y88942D01*
X31643D01*
Y88931D01*
X31632D01*
Y88896D01*
X31620D01*
Y88885D01*
X31597D01*
Y88850D01*
X31586D01*
Y88827D01*
X31574D01*
Y88781D01*
X31563D01*
Y88746D01*
X31551D01*
Y88735D01*
X31540D01*
Y88712D01*
X31528D01*
Y88689D01*
X31517D01*
Y88654D01*
X31493D01*
Y88620D01*
X31482D01*
Y88597D01*
X31471D01*
Y88574D01*
X31459D01*
Y88562D01*
X31447D01*
Y88528D01*
X31436D01*
Y88516D01*
X31413D01*
Y88505D01*
X31424D01*
Y88481D01*
X31413D01*
Y88459D01*
X31401D01*
Y88436D01*
X31390D01*
Y88424D01*
X31378D01*
Y88401D01*
X31367D01*
Y88389D01*
X31355D01*
Y88366D01*
X31344D01*
Y88355D01*
X31332D01*
Y88343D01*
X31321D01*
Y88320D01*
X31309D01*
Y88286D01*
X31298D01*
Y88274D01*
X31286D01*
Y88228D01*
X31252D01*
Y88217D01*
X31263D01*
Y88205D01*
X31252D01*
Y88194D01*
X31240D01*
Y88171D01*
X31229D01*
Y88148D01*
X31217D01*
Y88136D01*
X31206D01*
Y88125D01*
X31194D01*
Y88090D01*
X31183D01*
Y88078D01*
X31171D01*
Y88067D01*
X31159D01*
Y88032D01*
X31148D01*
Y87998D01*
X31137D01*
Y87975D01*
X31113D01*
Y87963D01*
X31102D01*
Y87940D01*
X31090D01*
Y87917D01*
X31079D01*
Y87894D01*
X31067D01*
Y87860D01*
X31056D01*
Y87791D01*
X31044D01*
Y87779D01*
X31033D01*
Y87756D01*
X31021D01*
Y87721D01*
X30998D01*
Y87698D01*
X30987D01*
Y87687D01*
X30975D01*
Y87652D01*
X30964D01*
Y87618D01*
X30952D01*
Y87595D01*
X30941D01*
Y87583D01*
X30929D01*
Y87560D01*
X30918D01*
Y87537D01*
X30906D01*
Y87491D01*
X30918D01*
Y87480D01*
X30906D01*
Y87468D01*
X30895D01*
Y87457D01*
X30883D01*
Y87422D01*
X30872D01*
Y87364D01*
X30860D01*
Y87330D01*
X30849D01*
Y87318D01*
X30837D01*
Y87307D01*
X30825D01*
Y87272D01*
X30814D01*
Y87238D01*
X30803D01*
Y87215D01*
X30814D01*
Y87192D01*
X30791D01*
Y87169D01*
X30779D01*
Y87157D01*
X30768D01*
Y87099D01*
X30756D01*
Y87065D01*
X30745D01*
Y87019D01*
X30733D01*
Y87007D01*
X30722D01*
Y86996D01*
X30733D01*
Y86984D01*
X30722D01*
Y86938D01*
X30710D01*
Y86927D01*
X30699D01*
Y86915D01*
X30676D01*
Y86846D01*
X30664D01*
Y86800D01*
X30653D01*
Y86789D01*
X30641D01*
Y86754D01*
X30630D01*
Y86720D01*
X30618D01*
Y86696D01*
X30607D01*
Y86685D01*
X30595D01*
Y86639D01*
X30584D01*
Y86581D01*
X30572D01*
Y86570D01*
X30561D01*
Y86535D01*
X30549D01*
Y86524D01*
X30538D01*
Y86478D01*
X30526D01*
Y86432D01*
X30515D01*
Y86420D01*
X30503D01*
Y86386D01*
X30492D01*
Y86339D01*
X30480D01*
Y86316D01*
X30468D01*
Y86305D01*
X30457D01*
Y86259D01*
X30446D01*
Y86236D01*
X30434D01*
Y86201D01*
X30422D01*
Y86190D01*
X30411D01*
Y86178D01*
X30399D01*
Y86167D01*
X30388D01*
Y86155D01*
X30399D01*
Y86144D01*
X30388D01*
Y86086D01*
X30376D01*
Y86075D01*
X30365D01*
Y86063D01*
X30353D01*
Y86051D01*
X30365D01*
Y86028D01*
X30353D01*
Y86006D01*
X30342D01*
Y85994D01*
X30307D01*
Y85959D01*
X30296D01*
Y85867D01*
X30261D01*
Y85821D01*
X30250D01*
Y85810D01*
X30238D01*
Y85787D01*
X30227D01*
Y85775D01*
X30215D01*
Y85787D01*
X30204D01*
Y85764D01*
X30215D01*
Y85718D01*
X30204D01*
Y85706D01*
X30192D01*
Y85683D01*
X30204D01*
Y85672D01*
X30192D01*
Y85660D01*
X30181D01*
Y85649D01*
X30169D01*
Y85637D01*
X30181D01*
Y85625D01*
X30158D01*
Y85602D01*
X30169D01*
Y85579D01*
X30146D01*
Y85533D01*
X30135D01*
Y85522D01*
X30123D01*
Y85499D01*
X30112D01*
Y85487D01*
X30146D01*
Y85476D01*
X30135D01*
Y85464D01*
X30123D01*
Y85418D01*
X30112D01*
Y85441D01*
X30100D01*
Y85430D01*
X30088D01*
Y85418D01*
X30077D01*
Y85395D01*
X30100D01*
Y85372D01*
X30088D01*
Y85361D01*
X30077D01*
Y85372D01*
X30065D01*
Y85384D01*
X30019D01*
Y85407D01*
X30008D01*
Y85372D01*
X29996D01*
Y85361D01*
X29985D01*
Y85349D01*
X29973D01*
Y85303D01*
X29962D01*
Y85291D01*
X29950D01*
Y85315D01*
X29916D01*
Y85326D01*
X29893D01*
Y85291D01*
X29881D01*
Y85303D01*
X29870D01*
Y85291D01*
X29858D01*
Y85280D01*
X29847D01*
Y85268D01*
X29835D01*
Y85315D01*
X29847D01*
Y85326D01*
X29858D01*
Y85361D01*
X29824D01*
Y85349D01*
X29812D01*
Y85338D01*
X29801D01*
Y85326D01*
X29789D01*
Y85291D01*
X29778D01*
Y85280D01*
X29766D01*
Y85315D01*
X29778D01*
Y85349D01*
X29789D01*
Y85418D01*
X29801D01*
Y85430D01*
X29812D01*
Y85487D01*
X29824D01*
Y85499D01*
X29835D01*
Y85556D01*
X29824D01*
Y85533D01*
X29812D01*
Y85510D01*
X29801D01*
Y85487D01*
X29789D01*
Y85430D01*
X29766D01*
Y85464D01*
X29778D01*
Y85545D01*
X29766D01*
Y85533D01*
X29754D01*
Y85499D01*
X29743D01*
Y85464D01*
X29732D01*
Y85441D01*
X29720D01*
Y85430D01*
X29708D01*
Y85418D01*
X29697D01*
Y85407D01*
X29720D01*
Y85418D01*
X29732D01*
Y85384D01*
X29720D01*
Y85395D01*
X29697D01*
Y85361D01*
X29685D01*
Y85338D01*
X29662D01*
Y85326D01*
X29639D01*
Y85338D01*
X29628D01*
Y85349D01*
X29616D01*
Y85407D01*
X29628D01*
Y85453D01*
X29616D01*
Y85522D01*
X29628D01*
Y85614D01*
X29616D01*
Y85637D01*
X29628D01*
Y85649D01*
X29616D01*
Y85706D01*
X29628D01*
Y85718D01*
X29639D01*
Y85729D01*
X29628D01*
Y85741D01*
X29639D01*
Y85775D01*
X29628D01*
Y85971D01*
X29616D01*
Y85982D01*
X29605D01*
Y86040D01*
X29593D01*
Y86155D01*
X29582D01*
Y86305D01*
X29570D01*
Y86328D01*
X29559D01*
Y86339D01*
X29570D01*
Y86362D01*
X29559D01*
Y86386D01*
X29547D01*
Y86535D01*
X29536D01*
Y86581D01*
X29524D01*
Y86593D01*
X29513D01*
Y86627D01*
X29524D01*
Y86662D01*
X29513D01*
Y86685D01*
X29501D01*
Y86766D01*
X29490D01*
Y86858D01*
X29478D01*
Y86892D01*
X29467D01*
Y86927D01*
X29478D01*
Y86938D01*
X29467D01*
Y86950D01*
X29444D01*
Y86996D01*
X29455D01*
Y87042D01*
X29444D01*
Y87019D01*
X29432D01*
Y87054D01*
X29421D01*
Y87065D01*
X29409D01*
Y87123D01*
X29397D01*
Y87192D01*
X29386D01*
Y87249D01*
X29375D01*
Y87261D01*
X29363D01*
Y87330D01*
X29351D01*
Y87410D01*
X29340D01*
Y87457D01*
X29328D01*
Y87503D01*
X29317D01*
Y87526D01*
X29305D01*
Y87560D01*
X29294D01*
Y87629D01*
X29282D01*
Y87641D01*
X29271D01*
Y87698D01*
X29259D01*
Y87756D01*
X29248D01*
Y87779D01*
X29259D01*
Y87791D01*
X29248D01*
Y87825D01*
X29236D01*
Y87848D01*
X29225D01*
Y87894D01*
X29213D01*
Y87986D01*
X29248D01*
Y88044D01*
X29236D01*
Y88055D01*
X29225D01*
Y88078D01*
X29213D01*
Y88090D01*
X29225D01*
Y88113D01*
X29213D01*
Y88125D01*
X29202D01*
Y88113D01*
X29190D01*
Y88102D01*
X29179D01*
Y88148D01*
X29190D01*
Y88159D01*
X29202D01*
Y88182D01*
X29179D01*
Y88159D01*
X29167D01*
Y88182D01*
X29156D01*
Y88194D01*
X29167D01*
Y88240D01*
X29156D01*
Y88297D01*
X29144D01*
Y88309D01*
X29133D01*
Y88320D01*
X29121D01*
Y88332D01*
X29133D01*
Y88355D01*
X29144D01*
Y88378D01*
X29121D01*
Y88424D01*
X29110D01*
Y88436D01*
X29087D01*
Y88412D01*
X29063D01*
Y88424D01*
X29075D01*
Y88481D01*
X29087D01*
Y88516D01*
X29075D01*
Y88493D01*
X29063D01*
Y88505D01*
X29052D01*
Y88470D01*
X29041D01*
Y88447D01*
X29052D01*
Y88424D01*
X29041D01*
Y88389D01*
X29029D01*
Y88401D01*
X29017D01*
Y88355D01*
X29006D01*
Y88343D01*
X28994D01*
Y88320D01*
X29017D01*
Y88343D01*
X29029D01*
Y88309D01*
X29017D01*
Y88286D01*
X29006D01*
Y88274D01*
X28994D01*
Y88263D01*
X28983D01*
Y88228D01*
X28971D01*
Y88171D01*
X28960D01*
Y88159D01*
X28948D01*
Y88125D01*
X28937D01*
Y88090D01*
X28948D01*
Y88067D01*
X28937D01*
Y88078D01*
X28925D01*
Y88055D01*
X28937D01*
Y88021D01*
X28925D01*
Y87998D01*
X28914D01*
Y87986D01*
X28902D01*
Y87975D01*
X28891D01*
Y87940D01*
X28879D01*
Y87883D01*
X28868D01*
Y87871D01*
X28856D01*
Y87860D01*
X28845D01*
Y87848D01*
X28856D01*
Y87837D01*
X28845D01*
Y87814D01*
X28856D01*
Y87802D01*
X28845D01*
Y87779D01*
X28833D01*
Y87733D01*
X28822D01*
Y87721D01*
X28810D01*
Y87698D01*
X28799D01*
Y87664D01*
X28787D01*
Y87618D01*
X28776D01*
Y87606D01*
X28764D01*
Y87595D01*
X28776D01*
Y87583D01*
X28764D01*
Y87572D01*
X28753D01*
Y87526D01*
X28741D01*
Y87503D01*
X28730D01*
Y87491D01*
X28718D01*
Y87468D01*
X28706D01*
Y87422D01*
X28695D01*
Y87399D01*
X28684D01*
Y87353D01*
X28672D01*
Y87341D01*
X28660D01*
Y87295D01*
X28649D01*
Y87261D01*
X28637D01*
Y87238D01*
X28626D01*
Y87215D01*
X28614D01*
Y87169D01*
X28603D01*
Y87134D01*
X28591D01*
Y87099D01*
X28580D01*
Y87088D01*
X28568D01*
Y87065D01*
X28557D01*
Y87030D01*
X28545D01*
Y86984D01*
X28534D01*
Y86973D01*
X28522D01*
Y86961D01*
X28488D01*
Y86950D01*
X28511D01*
Y86938D01*
X28499D01*
Y86892D01*
X28488D01*
Y86881D01*
X28476D01*
Y86858D01*
X28465D01*
Y86869D01*
X28453D01*
Y86858D01*
X28465D01*
Y86835D01*
X28442D01*
Y86812D01*
X28453D01*
Y86789D01*
X28442D01*
Y86777D01*
X28430D01*
Y86754D01*
X28419D01*
Y86731D01*
X28407D01*
Y86720D01*
X28384D01*
Y86685D01*
X28372D01*
Y86673D01*
X28350D01*
Y86662D01*
X28338D01*
Y86650D01*
X28326D01*
Y86639D01*
X28315D01*
Y86627D01*
X28326D01*
Y86616D01*
X28338D01*
Y86581D01*
X28326D01*
Y86570D01*
X28315D01*
Y86547D01*
X28303D01*
Y86535D01*
X28292D01*
Y86524D01*
X28280D01*
Y86512D01*
X28269D01*
Y86478D01*
X28257D01*
Y86501D01*
X28234D01*
Y86466D01*
X28223D01*
Y86455D01*
X28211D01*
Y86443D01*
X28165D01*
Y86432D01*
X28154D01*
Y86420D01*
X28142D01*
Y86443D01*
X28096D01*
Y86420D01*
X28073D01*
Y86432D01*
X28050D01*
Y86420D01*
X28062D01*
Y86409D01*
X28073D01*
Y86374D01*
X28038D01*
Y86386D01*
X28050D01*
Y86397D01*
X28016D01*
Y86409D01*
X28004D01*
Y86420D01*
X27992D01*
Y86432D01*
X27981D01*
Y86443D01*
X27958D01*
Y86420D01*
X27935D01*
Y86386D01*
X27900D01*
Y86432D01*
X27877D01*
Y86420D01*
X27866D01*
Y86409D01*
X27843D01*
Y86432D01*
X27831D01*
Y86443D01*
X27774D01*
Y86432D01*
X27751D01*
Y86443D01*
X27716D01*
Y86455D01*
X27705D01*
Y86466D01*
X27693D01*
Y86489D01*
X27681D01*
Y86501D01*
X27670D01*
Y86512D01*
X27659D01*
Y86558D01*
X27647D01*
Y86581D01*
X27659D01*
Y86593D01*
X27670D01*
Y86616D01*
X27647D01*
Y86639D01*
X27635D01*
Y86662D01*
X27647D01*
Y86685D01*
X27635D01*
Y86696D01*
X27624D01*
Y86743D01*
X27612D01*
Y86789D01*
X27601D01*
Y86881D01*
X27589D01*
Y86892D01*
X27578D01*
Y86984D01*
X27566D01*
Y87099D01*
X27555D01*
Y87192D01*
X27543D01*
Y87203D01*
X27532D01*
Y87422D01*
X27520D01*
Y87514D01*
X27509D01*
Y87572D01*
X27520D01*
Y87606D01*
X27509D01*
Y87710D01*
X27497D01*
Y87756D01*
X27486D01*
Y87883D01*
X27474D01*
Y87975D01*
X27463D01*
Y87986D01*
X27474D01*
Y87998D01*
X27463D01*
Y88044D01*
X27451D01*
Y88055D01*
X27440D01*
Y88078D01*
X27451D01*
Y88102D01*
X27440D01*
Y88217D01*
X27428D01*
Y88240D01*
X27440D01*
Y88274D01*
X27428D01*
Y88378D01*
X27417D01*
Y88424D01*
X27428D01*
Y88447D01*
X27417D01*
Y88505D01*
X27405D01*
Y88516D01*
X27394D01*
Y88574D01*
X27405D01*
Y88585D01*
X27394D01*
Y88597D01*
X27382D01*
Y88769D01*
X27371D01*
Y88931D01*
X27359D01*
Y88965D01*
X27348D01*
Y88977D01*
X27359D01*
Y88988D01*
X27348D01*
Y89011D01*
X27336D01*
Y89115D01*
X27290D01*
Y89103D01*
X27278D01*
Y89115D01*
X27255D01*
Y89103D01*
X27175D01*
Y89092D01*
X27163D01*
Y89080D01*
X27152D01*
Y89069D01*
X27083D01*
Y89057D01*
X27025D01*
Y89046D01*
X27002D01*
Y89034D01*
X26956D01*
Y89023D01*
X26910D01*
Y89011D01*
X26887D01*
Y89000D01*
X26841D01*
Y88988D01*
X26795D01*
Y88977D01*
X26760D01*
Y88965D01*
X26703D01*
Y88954D01*
X26691D01*
Y88942D01*
X26668D01*
Y88931D01*
X26680D01*
Y88919D01*
X26610D01*
Y88908D01*
X26576D01*
Y88896D01*
X26484D01*
Y88885D01*
X26380D01*
Y88873D01*
X26357D01*
Y88885D01*
X26346D01*
Y88873D01*
X26288D01*
Y88862D01*
X26265D01*
Y88873D01*
X26242D01*
Y88862D01*
X26230D01*
Y88850D01*
X26161D01*
Y88838D01*
X26184D01*
Y88827D01*
X26150D01*
Y88815D01*
X26115D01*
Y88804D01*
X26104D01*
Y88815D01*
X26092D01*
Y88804D01*
X26058D01*
Y88815D01*
X26023D01*
Y88804D01*
X26012D01*
Y88793D01*
X25989D01*
Y88804D01*
X25943D01*
Y88815D01*
X25931D01*
Y88804D01*
X25919D01*
Y88793D01*
X25885D01*
Y88781D01*
X25873D01*
Y88804D01*
X25850D01*
Y88793D01*
X25839D01*
Y88769D01*
X25827D01*
Y88781D01*
X25816D01*
Y88758D01*
X25827D01*
Y88746D01*
X25804D01*
Y88735D01*
X25793D01*
Y88723D01*
X25770D01*
Y88712D01*
X25758D01*
Y88700D01*
X25735D01*
Y88689D01*
X25724D01*
Y88700D01*
X25701D01*
Y88689D01*
X25678D01*
Y88700D01*
X25666D01*
Y88723D01*
X25678D01*
Y88735D01*
X25643D01*
Y88723D01*
X25632D01*
Y88689D01*
X25643D01*
Y88700D01*
X25655D01*
Y88689D01*
X25666D01*
Y88677D01*
X25655D01*
Y88666D01*
X25643D01*
Y88654D01*
X25632D01*
Y88643D01*
X25585D01*
Y88689D01*
X25551D01*
Y88677D01*
X25528D01*
Y88666D01*
X25505D01*
Y88677D01*
X25459D01*
Y88666D01*
X25424D01*
Y88677D01*
X25413D01*
Y88689D01*
X25424D01*
Y88700D01*
X25436D01*
Y88735D01*
X25447D01*
Y88769D01*
X25459D01*
Y88781D01*
X25470D01*
Y88769D01*
X25493D01*
Y88781D01*
X25482D01*
Y88804D01*
X25505D01*
Y88827D01*
X25482D01*
Y88815D01*
X25459D01*
Y88804D01*
X25447D01*
Y88793D01*
X25424D01*
Y88781D01*
X25413D01*
Y88769D01*
X25401D01*
Y88758D01*
X25390D01*
Y88746D01*
X25413D01*
Y88735D01*
X25355D01*
Y88746D01*
X25332D01*
Y88735D01*
X25309D01*
Y88746D01*
X25286D01*
Y88769D01*
X25275D01*
Y88781D01*
X25263D01*
Y88793D01*
X25275D01*
Y88804D01*
X25286D01*
Y88827D01*
X25298D01*
Y88862D01*
X25286D01*
Y88885D01*
X25275D01*
Y88896D01*
X25286D01*
Y88977D01*
X25298D01*
Y89000D01*
X25286D01*
Y89023D01*
X25309D01*
Y89034D01*
X25298D01*
Y89069D01*
X25309D01*
Y89080D01*
X25321D01*
Y89057D01*
X25344D01*
Y89080D01*
X25367D01*
Y89092D01*
X25378D01*
Y89103D01*
X25390D01*
Y89126D01*
X25413D01*
Y89149D01*
X25424D01*
Y89161D01*
X25436D01*
Y89173D01*
X25447D01*
Y89184D01*
X25459D01*
Y89196D01*
X25470D01*
Y89207D01*
X25482D01*
Y89219D01*
X25493D01*
Y89230D01*
X25505D01*
Y89242D01*
X25516D01*
Y89253D01*
X25528D01*
Y89265D01*
X25551D01*
Y89276D01*
X25563D01*
Y89288D01*
X25574D01*
Y89311D01*
X25585D01*
Y89322D01*
X25597D01*
Y89345D01*
X25585D01*
Y89380D01*
X25597D01*
Y89414D01*
X25609D01*
Y89391D01*
X25643D01*
Y89403D01*
X25632D01*
Y89414D01*
X25620D01*
Y89437D01*
X25632D01*
Y89460D01*
X25643D01*
Y89472D01*
X25666D01*
Y89483D01*
X25678D01*
Y89507D01*
X25689D01*
Y89541D01*
X25724D01*
Y89553D01*
X25735D01*
Y89587D01*
X25770D01*
Y89610D01*
X25735D01*
Y89622D01*
X25747D01*
Y89633D01*
X25781D01*
Y89645D01*
X25770D01*
Y89656D01*
X25781D01*
Y89691D01*
X25770D01*
Y89702D01*
X25781D01*
Y89691D01*
X25793D01*
Y89679D01*
X25816D01*
Y89691D01*
X25804D01*
Y89714D01*
X25827D01*
Y89691D01*
X25839D01*
Y89679D01*
X25850D01*
Y89725D01*
X25862D01*
Y89737D01*
X25850D01*
Y89748D01*
X25862D01*
Y89737D01*
X25873D01*
Y89714D01*
X25885D01*
Y89725D01*
X25896D01*
Y89737D01*
X25919D01*
Y89748D01*
X25931D01*
Y89771D01*
X25954D01*
Y89783D01*
X25966D01*
Y89794D01*
X25977D01*
Y89806D01*
X25989D01*
Y89852D01*
X26012D01*
Y89875D01*
X26035D01*
Y89910D01*
X26058D01*
Y89921D01*
X26046D01*
Y89933D01*
X26081D01*
Y89944D01*
X26092D01*
Y89956D01*
X26104D01*
Y89979D01*
X26115D01*
Y89967D01*
X26127D01*
Y90002D01*
X26138D01*
Y90013D01*
X26150D01*
Y90025D01*
X26161D01*
Y90036D01*
X26173D01*
Y90048D01*
X26184D01*
Y90071D01*
X26219D01*
Y90094D01*
X26196D01*
Y90105D01*
X26254D01*
Y90117D01*
X26230D01*
Y90128D01*
X26196D01*
Y90117D01*
X26138D01*
Y90105D01*
X26115D01*
Y90094D01*
X26104D01*
Y90071D01*
X26115D01*
Y90059D01*
X26104D01*
Y90048D01*
X26069D01*
Y90059D01*
X26081D01*
Y90071D01*
X26035D01*
Y90059D01*
X26012D01*
Y90048D01*
X26000D01*
Y90059D01*
X25977D01*
Y90048D01*
X25966D01*
Y90013D01*
X26012D01*
Y90002D01*
X26000D01*
Y89990D01*
X25989D01*
Y89979D01*
X25977D01*
Y89967D01*
X25943D01*
Y89956D01*
X25931D01*
Y89967D01*
X25919D01*
Y89979D01*
X25908D01*
Y90002D01*
X25919D01*
Y90025D01*
X25931D01*
Y90013D01*
X25954D01*
Y90036D01*
X25943D01*
Y90048D01*
X25919D01*
Y90071D01*
X25931D01*
Y90094D01*
X25919D01*
Y90105D01*
X25908D01*
Y90128D01*
X25919D01*
Y90105D01*
X25931D01*
Y90128D01*
X25943D01*
Y90140D01*
X25954D01*
Y90151D01*
X25966D01*
Y90163D01*
X25977D01*
Y90175D01*
X25989D01*
Y90186D01*
X26000D01*
Y90197D01*
X26012D01*
Y90220D01*
X26023D01*
Y90232D01*
X26035D01*
Y90244D01*
X26046D01*
Y90255D01*
X26058D01*
Y90244D01*
X26069D01*
Y90255D01*
X26081D01*
Y90267D01*
X26092D01*
Y90278D01*
X26104D01*
Y90290D01*
X26115D01*
Y90301D01*
X26127D01*
Y90313D01*
X26138D01*
Y90324D01*
X26150D01*
Y90336D01*
X26161D01*
Y90347D01*
X26173D01*
Y90359D01*
X26184D01*
Y90382D01*
X26207D01*
Y90405D01*
X26230D01*
Y90416D01*
X26242D01*
Y90428D01*
X26219D01*
Y90451D01*
X26242D01*
Y90428D01*
X26254D01*
Y90439D01*
X26288D01*
Y90451D01*
X26300D01*
Y90462D01*
X26311D01*
Y90474D01*
X26346D01*
Y90485D01*
X26357D01*
Y90497D01*
X26369D01*
Y90508D01*
X26380D01*
Y90497D01*
X26392D01*
Y90531D01*
X26346D01*
Y90543D01*
X26334D01*
Y90578D01*
X26357D01*
Y90589D01*
X26369D01*
Y90601D01*
X26380D01*
Y90612D01*
X26392D01*
Y90624D01*
X26403D01*
Y90635D01*
X26415D01*
Y90647D01*
X26426D01*
Y90658D01*
X26438D01*
Y90681D01*
X26461D01*
Y90693D01*
X26472D01*
Y90716D01*
X26484D01*
Y90727D01*
X26507D01*
Y90739D01*
X26518D01*
Y90762D01*
X26530D01*
Y90773D01*
X26541D01*
Y90785D01*
X26564D01*
Y90796D01*
X26576D01*
Y90808D01*
X26588D01*
Y90819D01*
X26599D01*
Y90831D01*
X26610D01*
Y90842D01*
X26622D01*
Y90854D01*
X26634D01*
Y90865D01*
X26645D01*
Y90877D01*
X26656D01*
Y90889D01*
X26668D01*
Y90900D01*
X26691D01*
Y90912D01*
X26703D01*
Y90923D01*
X26714D01*
Y90935D01*
X26726D01*
Y90958D01*
X26760D01*
Y90992D01*
X26783D01*
Y91004D01*
X26795D01*
Y91015D01*
X26818D01*
Y91050D01*
X26829D01*
Y91061D01*
X26852D01*
Y91084D01*
X26864D01*
Y91096D01*
X26887D01*
Y91107D01*
X26898D01*
Y91119D01*
X26910D01*
Y91130D01*
X26921D01*
Y91142D01*
X26933D01*
Y91153D01*
X26956D01*
Y91176D01*
X26967D01*
Y91188D01*
X26991D01*
Y91199D01*
X27002D01*
Y91211D01*
X27014D01*
Y91223D01*
X27025D01*
Y91257D01*
X27014D01*
Y91268D01*
X27002D01*
Y91372D01*
X26991D01*
Y91476D01*
X26979D01*
Y91487D01*
X26967D01*
Y91510D01*
X26956D01*
Y91580D01*
X26945D01*
Y91672D01*
X26933D01*
Y91695D01*
X26921D01*
Y91741D01*
X26910D01*
Y91764D01*
X26921D01*
Y91787D01*
X26910D01*
Y91798D01*
X26898D01*
Y91856D01*
X26910D01*
Y91890D01*
X26898D01*
Y91913D01*
X26887D01*
Y91948D01*
X26875D01*
Y91994D01*
X26864D01*
Y92086D01*
X26852D01*
Y92132D01*
X26841D01*
Y92178D01*
X26829D01*
Y92201D01*
X26818D01*
Y92282D01*
X26806D01*
Y92374D01*
X26795D01*
Y92409D01*
X26783D01*
Y92432D01*
X26772D01*
Y92501D01*
X26760D01*
Y92604D01*
X26749D01*
Y92628D01*
X26737D01*
Y92639D01*
X26749D01*
Y92685D01*
X26737D01*
Y92697D01*
X26726D01*
Y92754D01*
X26714D01*
Y92812D01*
X26703D01*
Y92835D01*
X26691D01*
Y92858D01*
X26680D01*
Y92938D01*
X26668D01*
Y93019D01*
X26656D01*
Y93134D01*
X26645D01*
Y93146D01*
X26634D01*
Y93238D01*
X26622D01*
Y93353D01*
X26610D01*
Y93388D01*
X26599D01*
Y93411D01*
X26588D01*
Y93445D01*
X26576D01*
Y93457D01*
X26588D01*
Y93480D01*
X26576D01*
Y93537D01*
X26564D01*
Y93572D01*
X26553D01*
Y93606D01*
X26541D01*
Y93652D01*
X26530D01*
Y93710D01*
X26518D01*
Y93756D01*
X26507D01*
Y93814D01*
X26495D01*
Y93837D01*
X26484D01*
Y93906D01*
X26472D01*
Y93975D01*
X26495D01*
Y93986D01*
X26507D01*
Y93998D01*
X26495D01*
Y94033D01*
X26484D01*
Y94090D01*
X26495D01*
Y94125D01*
X26530D01*
Y94136D01*
X26541D01*
Y94148D01*
X26553D01*
Y94159D01*
X26576D01*
Y94125D01*
X26588D01*
Y94113D01*
X26599D01*
Y94125D01*
X26610D01*
Y94148D01*
X26599D01*
Y94159D01*
X26588D01*
Y94182D01*
X26599D01*
Y94194D01*
X26610D01*
Y94182D01*
X26622D01*
Y94159D01*
X26656D01*
Y94171D01*
X26645D01*
Y94182D01*
X26634D01*
Y94194D01*
X26703D01*
Y94159D01*
X26714D01*
Y94067D01*
X26760D01*
Y94055D01*
X26772D01*
Y94090D01*
X26783D01*
Y94102D01*
X26806D01*
Y94159D01*
X26818D01*
Y94148D01*
X26852D01*
Y94136D01*
X26875D01*
Y94148D01*
X26864D01*
Y94171D01*
X26875D01*
Y94182D01*
X26887D01*
Y94194D01*
X26898D01*
Y94297D01*
X26910D01*
Y94240D01*
X26933D01*
Y94228D01*
X26945D01*
Y94205D01*
X26956D01*
Y94240D01*
X26945D01*
Y94297D01*
X26956D01*
Y94309D01*
X26945D01*
Y94332D01*
X26956D01*
Y94355D01*
X26967D01*
Y94378D01*
X26956D01*
Y94424D01*
X26945D01*
Y94528D01*
X26956D01*
Y94539D01*
X26945D01*
Y94585D01*
X26956D01*
Y94620D01*
X26967D01*
Y94608D01*
X26979D01*
Y94597D01*
X27002D01*
Y94631D01*
X27014D01*
Y94620D01*
X27025D01*
Y94608D01*
X27037D01*
Y94597D01*
X27048D01*
Y94551D01*
X27060D01*
Y94482D01*
X27083D01*
Y94493D01*
X27117D01*
Y94505D01*
X27129D01*
Y94528D01*
X27140D01*
Y94539D01*
X27129D01*
Y94585D01*
X27140D01*
Y94608D01*
X27129D01*
Y94677D01*
X27152D01*
Y94689D01*
X27163D01*
Y94574D01*
X27198D01*
Y94643D01*
X27209D01*
Y94666D01*
X27198D01*
Y94747D01*
X27186D01*
Y94770D01*
X27221D01*
Y94781D01*
X27232D01*
Y94758D01*
X27244D01*
Y94723D01*
X27255D01*
Y94700D01*
X27267D01*
Y94689D01*
X27278D01*
Y94700D01*
X27301D01*
Y94689D01*
X27313D01*
Y94677D01*
X27336D01*
Y94631D01*
X27359D01*
Y94666D01*
X27371D01*
Y94677D01*
X27382D01*
Y94666D01*
X27394D01*
Y94677D01*
X27405D01*
Y94689D01*
X27394D01*
Y94700D01*
X27405D01*
Y94712D01*
X27417D01*
Y94735D01*
X27405D01*
Y94781D01*
X27394D01*
Y94816D01*
X27382D01*
Y94850D01*
X27371D01*
Y94919D01*
X27359D01*
Y94942D01*
X27371D01*
Y95000D01*
X27359D01*
Y95034D01*
X27371D01*
Y95046D01*
X27359D01*
Y95081D01*
X27371D01*
Y95104D01*
X27382D01*
Y95138D01*
X27371D01*
Y95161D01*
X27394D01*
Y95104D01*
X27417D01*
Y95081D01*
X27394D01*
Y95092D01*
X27382D01*
Y95000D01*
X27394D01*
Y94988D01*
X27405D01*
Y94977D01*
X27417D01*
Y94965D01*
X27405D01*
Y94954D01*
X27394D01*
Y94942D01*
X27417D01*
Y94954D01*
X27428D01*
Y95000D01*
X27417D01*
Y95023D01*
X27428D01*
Y95011D01*
X27440D01*
Y94942D01*
X27428D01*
Y94862D01*
X27440D01*
Y94850D01*
X27428D01*
Y94827D01*
X27440D01*
Y94816D01*
X27428D01*
Y94804D01*
X27451D01*
Y94781D01*
X27440D01*
Y94770D01*
X27463D01*
Y94781D01*
X27474D01*
Y94770D01*
X27486D01*
Y94758D01*
X27509D01*
Y94781D01*
X27497D01*
Y94804D01*
X27509D01*
Y94816D01*
X27486D01*
Y94827D01*
X27474D01*
Y94862D01*
X27486D01*
Y94873D01*
X27497D01*
Y94896D01*
X27486D01*
Y94908D01*
X27474D01*
Y94919D01*
X27532D01*
Y94942D01*
X27543D01*
Y94954D01*
X27555D01*
Y94965D01*
X27566D01*
Y94954D01*
X27589D01*
Y94919D01*
X27612D01*
Y94850D01*
X27624D01*
Y94816D01*
X27612D01*
Y94770D01*
X27624D01*
Y94747D01*
X27612D01*
Y94758D01*
X27601D01*
Y94747D01*
X27589D01*
Y94735D01*
X27601D01*
Y94723D01*
X27612D01*
Y94643D01*
X27601D01*
Y94562D01*
X27612D01*
Y94551D01*
X27578D01*
Y94516D01*
X27601D01*
Y94528D01*
X27612D01*
Y94505D01*
X27624D01*
Y94470D01*
X27635D01*
Y94424D01*
X27659D01*
Y94493D01*
X27647D01*
Y94562D01*
X27659D01*
Y94551D01*
X27670D01*
Y94482D01*
X27681D01*
Y94436D01*
X27693D01*
Y94401D01*
X27705D01*
Y94378D01*
X27716D01*
Y94286D01*
X27728D01*
Y94228D01*
X27739D01*
Y94217D01*
X27751D01*
Y94205D01*
X27728D01*
Y94217D01*
X27716D01*
Y94240D01*
X27705D01*
Y94332D01*
X27693D01*
Y94367D01*
X27681D01*
Y94378D01*
X27670D01*
Y94401D01*
X27659D01*
Y94343D01*
X27670D01*
Y94286D01*
X27681D01*
Y94240D01*
X27693D01*
Y94228D01*
X27705D01*
Y94148D01*
X27716D01*
Y94182D01*
X27739D01*
Y94171D01*
X27751D01*
Y94159D01*
X27762D01*
Y94136D01*
X27751D01*
Y94090D01*
X27762D01*
Y94102D01*
X27774D01*
Y94090D01*
X27785D01*
Y94067D01*
X27762D01*
Y94010D01*
X27797D01*
Y93998D01*
X27808D01*
Y93986D01*
X27820D01*
Y93952D01*
X27808D01*
Y93963D01*
Y93975D01*
X27797D01*
Y93998D01*
X27785D01*
Y93986D01*
X27774D01*
Y93940D01*
X27785D01*
Y93917D01*
X27808D01*
Y93883D01*
X27820D01*
Y93871D01*
X27831D01*
Y93825D01*
X27843D01*
Y93814D01*
X27854D01*
Y93756D01*
X27843D01*
Y93745D01*
X27831D01*
Y93687D01*
X27808D01*
Y93676D01*
X27820D01*
Y93606D01*
X27808D01*
Y93618D01*
X27797D01*
Y93595D01*
X27820D01*
Y93514D01*
X27831D01*
Y93503D01*
X27808D01*
Y93480D01*
X27820D01*
Y93422D01*
X27831D01*
Y93411D01*
X27843D01*
Y93330D01*
X27854D01*
Y93249D01*
X27866D01*
Y93146D01*
X27877D01*
Y93134D01*
X27889D01*
Y93065D01*
X27900D01*
Y93042D01*
X27889D01*
Y92996D01*
X27900D01*
Y92927D01*
X27889D01*
Y92881D01*
X27900D01*
Y92777D01*
X27912D01*
Y92743D01*
X27900D01*
Y92708D01*
X27912D01*
Y92697D01*
X27900D01*
Y92616D01*
X27912D01*
Y92547D01*
X27900D01*
Y92535D01*
X27912D01*
Y92524D01*
X27923D01*
Y92512D01*
X27935D01*
Y92489D01*
X27923D01*
Y92478D01*
X27935D01*
Y92455D01*
X27923D01*
Y92443D01*
X27912D01*
Y92432D01*
X27923D01*
Y92420D01*
X27935D01*
Y92409D01*
X27946D01*
Y92397D01*
X27935D01*
Y92340D01*
X27946D01*
Y92270D01*
X27958D01*
Y92167D01*
X27969D01*
Y92155D01*
X27981D01*
Y92132D01*
X27992D01*
Y92144D01*
X28004D01*
Y92155D01*
X28027D01*
Y92167D01*
X28038D01*
Y92178D01*
X28050D01*
Y92190D01*
X28085D01*
Y92224D01*
X28131D01*
Y92213D01*
X28108D01*
Y92178D01*
X28073D01*
Y92155D01*
X28062D01*
Y92144D01*
X28050D01*
Y92132D01*
X28027D01*
Y92121D01*
X28016D01*
Y92109D01*
X28004D01*
Y92098D01*
X27992D01*
Y92075D01*
X27981D01*
Y92052D01*
X27992D01*
Y92029D01*
X27981D01*
Y91994D01*
X27992D01*
Y91983D01*
X28004D01*
Y91971D01*
X27992D01*
Y91948D01*
X28004D01*
Y91936D01*
X27992D01*
Y91833D01*
X28004D01*
Y91787D01*
X28016D01*
Y91764D01*
X28004D01*
Y91706D01*
X28027D01*
Y91764D01*
X28038D01*
Y91741D01*
X28062D01*
Y91752D01*
X28073D01*
Y91764D01*
X28085D01*
Y91775D01*
X28096D01*
Y91821D01*
X28119D01*
Y91833D01*
X28131D01*
Y91856D01*
X28142D01*
Y91879D01*
X28154D01*
Y91890D01*
X28177D01*
Y91936D01*
X28188D01*
Y91948D01*
X28223D01*
Y91971D01*
X28234D01*
Y91994D01*
X28246D01*
Y92006D01*
X28257D01*
Y92017D01*
X28269D01*
Y92040D01*
X28280D01*
Y92063D01*
X28292D01*
Y92075D01*
X28303D01*
Y92086D01*
X28315D01*
Y92121D01*
X28326D01*
Y92132D01*
X28338D01*
Y92144D01*
X28350D01*
Y92155D01*
X28315D01*
Y92132D01*
X28303D01*
Y92167D01*
X28315D01*
Y92178D01*
X28361D01*
Y92190D01*
X28338D01*
Y92236D01*
X28326D01*
Y92259D01*
X28315D01*
Y92247D01*
X28303D01*
Y92236D01*
X28292D01*
Y92224D01*
X28280D01*
Y92213D01*
X28269D01*
Y92201D01*
X28257D01*
Y92190D01*
X28234D01*
Y92178D01*
X28246D01*
Y92167D01*
X28211D01*
Y92155D01*
X28188D01*
Y92167D01*
X28177D01*
Y92190D01*
X28165D01*
Y92224D01*
X28177D01*
Y92259D01*
X28223D01*
Y92270D01*
X28211D01*
Y92282D01*
X28246D01*
Y92294D01*
X28257D01*
Y92305D01*
X28269D01*
Y92351D01*
X28257D01*
Y92363D01*
X28280D01*
Y92386D01*
X28292D01*
Y92397D01*
X28303D01*
Y92489D01*
X28292D01*
Y92501D01*
X28280D01*
Y92581D01*
X28269D01*
Y92639D01*
X28257D01*
Y92651D01*
X28269D01*
Y92662D01*
X28257D01*
Y92777D01*
X28269D01*
Y92846D01*
X28257D01*
Y92869D01*
X28269D01*
Y92881D01*
X28257D01*
Y92938D01*
X28246D01*
Y92950D01*
X28234D01*
Y93019D01*
X28223D01*
Y92938D01*
X28234D01*
Y92835D01*
X28223D01*
Y92927D01*
X28211D01*
Y93042D01*
X28200D01*
Y93054D01*
X28188D01*
Y93169D01*
X28177D01*
Y93249D01*
X28165D01*
Y93318D01*
X28154D01*
Y93330D01*
X28142D01*
Y93434D01*
X28131D01*
Y93537D01*
X28119D01*
Y93595D01*
X28108D01*
Y93606D01*
X28096D01*
Y93676D01*
X28085D01*
Y93779D01*
X28073D01*
Y93871D01*
X28062D01*
Y93883D01*
X28050D01*
Y93975D01*
X28038D01*
Y94021D01*
X28050D01*
Y94044D01*
X28038D01*
Y94113D01*
X28027D01*
Y94182D01*
X28016D01*
Y94205D01*
X28004D01*
Y94240D01*
X28016D01*
Y94251D01*
X28004D01*
Y94297D01*
X27992D01*
Y94389D01*
X27981D01*
Y94482D01*
X27969D01*
Y94516D01*
X27958D01*
Y94562D01*
X27969D01*
Y94608D01*
X27958D01*
Y94620D01*
X27946D01*
Y94816D01*
X27935D01*
Y94942D01*
X27923D01*
Y95023D01*
X27912D01*
Y95034D01*
X27900D01*
Y95127D01*
X27889D01*
Y95161D01*
X27877D01*
Y95196D01*
X27866D01*
Y95219D01*
X27877D01*
Y95242D01*
X27854D01*
Y95357D01*
X27843D01*
Y95415D01*
X27854D01*
Y95461D01*
X27843D01*
Y95576D01*
X27831D01*
Y95749D01*
X27854D01*
Y95864D01*
X27866D01*
Y95875D01*
X27877D01*
Y95921D01*
X27889D01*
Y95910D01*
X27900D01*
Y95898D01*
X27912D01*
Y95910D01*
X27923D01*
Y95956D01*
X27946D01*
Y95944D01*
X27958D01*
Y95956D01*
X27981D01*
Y95944D01*
X27992D01*
Y95990D01*
X28016D01*
Y96002D01*
X28038D01*
Y95990D01*
X28050D01*
Y95979D01*
X28062D01*
Y95967D01*
X28085D01*
Y95944D01*
X28096D01*
Y95910D01*
X28108D01*
Y95887D01*
X28096D01*
Y95875D01*
X28108D01*
Y95841D01*
X28131D01*
Y95852D01*
X28142D01*
Y95887D01*
X28154D01*
Y95898D01*
X28177D01*
Y95910D01*
X28188D01*
Y95967D01*
X28211D01*
Y95979D01*
X28223D01*
Y96082D01*
X28211D01*
Y96175D01*
X28223D01*
Y96186D01*
X28257D01*
Y96198D01*
X28269D01*
Y96221D01*
X28280D01*
Y96209D01*
X28303D01*
Y96313D01*
X28315D01*
Y96336D01*
X28326D01*
Y96324D01*
X28338D01*
Y96336D01*
X28350D01*
Y96347D01*
X28361D01*
Y96359D01*
X28372D01*
Y96393D01*
X28384D01*
Y96405D01*
X28396D01*
Y96393D01*
X28419D01*
Y96336D01*
X28430D01*
Y96347D01*
X28442D01*
Y96405D01*
X28465D01*
Y96474D01*
X28488D01*
Y96463D01*
X28476D01*
Y96416D01*
X28499D01*
Y96393D01*
X28511D01*
Y96255D01*
X28499D01*
Y96221D01*
X28522D01*
Y96232D01*
X28534D01*
Y96255D01*
X28522D01*
Y96278D01*
X28534D01*
Y96301D01*
X28522D01*
Y96324D01*
X28534D01*
Y96347D01*
X28557D01*
Y96324D01*
X28568D01*
Y96336D01*
X28591D01*
Y96324D01*
X28603D01*
Y96359D01*
X28591D01*
Y96347D01*
X28580D01*
Y96359D01*
X28568D01*
Y96382D01*
X28580D01*
Y96393D01*
X28591D01*
Y96439D01*
X28603D01*
Y96370D01*
X28614D01*
Y96359D01*
X28626D01*
Y96347D01*
X28649D01*
Y96359D01*
X28660D01*
Y96393D01*
X28649D01*
Y96382D01*
X28637D01*
Y96416D01*
X28649D01*
Y96405D01*
X28660D01*
Y96474D01*
X28672D01*
Y96486D01*
X28684D01*
Y96497D01*
X28672D01*
Y96509D01*
X28660D01*
Y96624D01*
X28649D01*
Y96635D01*
X28637D01*
Y96693D01*
X28649D01*
Y96727D01*
X28637D01*
Y96739D01*
X28626D01*
Y96785D01*
X28614D01*
Y96808D01*
X28626D01*
Y96831D01*
X28672D01*
Y96842D01*
X28684D01*
Y96900D01*
X28695D01*
Y96889D01*
X28706D01*
Y96877D01*
X28695D01*
Y96842D01*
X28706D01*
Y96854D01*
X28718D01*
Y96820D01*
X28741D01*
Y96866D01*
X28753D01*
Y96842D01*
X28764D01*
Y96797D01*
X28753D01*
Y96693D01*
X28764D01*
Y96624D01*
X28776D01*
Y96612D01*
X28787D01*
Y96601D01*
X28799D01*
Y96566D01*
X28810D01*
Y96578D01*
X28822D01*
Y96658D01*
X28810D01*
Y96670D01*
X28799D01*
Y96773D01*
X28787D01*
Y96820D01*
X28799D01*
Y96912D01*
X28810D01*
Y96923D01*
X28822D01*
Y96912D01*
D02*
G37*
G36*
X28557Y96428D02*
X28545D01*
Y96439D01*
X28557D01*
Y96428D01*
D02*
G37*
G36*
X28511D02*
X28522D01*
Y96416D01*
X28499D01*
Y96439D01*
X28511D01*
Y96428D01*
D02*
G37*
G36*
X28223Y96405D02*
X28211D01*
Y96416D01*
Y96428D01*
X28223D01*
Y96405D01*
D02*
G37*
G36*
X28188Y96393D02*
X28177D01*
Y96405D01*
Y96416D01*
X28188D01*
Y96393D01*
D02*
G37*
G36*
X28534Y96382D02*
X28522D01*
Y96393D01*
X28534D01*
Y96382D01*
D02*
G37*
G36*
X28188Y96347D02*
X28177D01*
Y96359D01*
X28188D01*
Y96347D01*
D02*
G37*
G36*
X28234Y96255D02*
X28223D01*
Y96278D01*
Y96290D01*
X28234D01*
Y96255D01*
D02*
G37*
G36*
X27359Y95127D02*
X27371D01*
Y95115D01*
X27359D01*
Y95104D01*
X27348D01*
Y95115D01*
X27336D01*
Y95127D01*
X27348D01*
Y95138D01*
X27359D01*
Y95127D01*
D02*
G37*
G36*
X27278Y95057D02*
X27267D01*
Y95069D01*
X27278D01*
Y95057D01*
D02*
G37*
G36*
X30722Y95161D02*
X30733D01*
Y95150D01*
X30745D01*
Y95092D01*
X30733D01*
Y95023D01*
X30710D01*
Y95115D01*
X30687D01*
Y95069D01*
X30676D01*
Y95092D01*
X30664D01*
Y95081D01*
X30653D01*
Y95069D01*
X30641D01*
Y95057D01*
X30630D01*
Y95046D01*
X30595D01*
Y95034D01*
X30584D01*
Y95057D01*
X30595D01*
Y95069D01*
X30607D01*
Y95081D01*
X30618D01*
Y95092D01*
X30630D01*
Y95104D01*
X30641D01*
Y95115D01*
X30653D01*
Y95138D01*
X30664D01*
Y95150D01*
X30676D01*
Y95161D01*
X30699D01*
Y95173D01*
X30722D01*
Y95161D01*
D02*
G37*
G36*
X30572Y95011D02*
X30561D01*
Y95023D01*
X30572D01*
Y95011D01*
D02*
G37*
G36*
X27336Y94965D02*
X27325D01*
Y94977D01*
X27336D01*
Y94965D01*
D02*
G37*
G36*
X30538Y94942D02*
X30526D01*
Y94931D01*
X30515D01*
Y94942D01*
Y94954D01*
X30538D01*
Y94942D01*
D02*
G37*
G36*
X30342Y94931D02*
X30330D01*
Y94942D01*
X30342D01*
Y94931D01*
D02*
G37*
G36*
X30353Y94896D02*
X30342D01*
Y94908D01*
X30353D01*
Y94896D01*
D02*
G37*
G36*
X27474D02*
X27463D01*
Y94908D01*
X27474D01*
Y94896D01*
D02*
G37*
G36*
X27255Y94908D02*
Y94896D01*
X27244D01*
Y94919D01*
X27255D01*
Y94908D01*
D02*
G37*
G36*
X30860Y94885D02*
X30849D01*
Y94896D01*
X30860D01*
Y94885D01*
D02*
G37*
G36*
X30492Y94919D02*
X30503D01*
Y94908D01*
X30492D01*
Y94885D01*
X30480D01*
Y94873D01*
Y94862D01*
X30468D01*
Y94931D01*
X30492D01*
Y94919D01*
D02*
G37*
G36*
X30399Y94896D02*
X30388D01*
Y94885D01*
X30376D01*
Y94873D01*
X30365D01*
Y94862D01*
X30353D01*
Y94839D01*
X30342D01*
Y94816D01*
X30307D01*
Y94804D01*
X30296D01*
Y94758D01*
X30284D01*
Y94747D01*
X30261D01*
Y94758D01*
X30238D01*
Y94770D01*
X30215D01*
Y94758D01*
X30204D01*
Y94712D01*
X30227D01*
Y94723D01*
X30238D01*
Y94712D01*
X30250D01*
Y94723D01*
X30238D01*
Y94735D01*
X30250D01*
Y94723D01*
X30261D01*
Y94689D01*
X30250D01*
Y94666D01*
X30238D01*
Y94677D01*
X30215D01*
Y94666D01*
X30227D01*
Y94643D01*
X30215D01*
Y94620D01*
X30204D01*
Y94631D01*
X30192D01*
Y94597D01*
X30181D01*
Y94585D01*
X30169D01*
Y94574D01*
X30158D01*
Y94562D01*
X30146D01*
Y94505D01*
X30112D01*
Y94493D01*
X30100D01*
Y94470D01*
X30088D01*
Y94459D01*
X30077D01*
Y94447D01*
X30065D01*
Y94436D01*
X30054D01*
Y94447D01*
X30031D01*
Y94436D01*
X30019D01*
Y94378D01*
X30008D01*
Y94389D01*
X29985D01*
Y94378D01*
X29973D01*
Y94367D01*
X29985D01*
Y94343D01*
X29973D01*
Y94320D01*
X29962D01*
Y94309D01*
X29950D01*
Y94297D01*
X29939D01*
Y94286D01*
X29927D01*
Y94274D01*
X29916D01*
Y94240D01*
X29904D01*
Y94228D01*
X29893D01*
Y94217D01*
X29881D01*
Y94205D01*
X29870D01*
Y94182D01*
X29858D01*
Y94171D01*
X29847D01*
Y94159D01*
X29835D01*
Y94125D01*
X29824D01*
Y94113D01*
X29801D01*
Y94102D01*
X29789D01*
Y94067D01*
X29778D01*
Y94079D01*
X29766D01*
Y94067D01*
X29778D01*
Y94055D01*
X29766D01*
Y94067D01*
X29743D01*
Y94055D01*
X29732D01*
Y94044D01*
X29708D01*
Y94033D01*
X29697D01*
Y94010D01*
X29685D01*
Y93998D01*
X29662D01*
Y93986D01*
X29651D01*
Y93952D01*
X29639D01*
Y93963D01*
X29616D01*
Y93940D01*
X29628D01*
Y93929D01*
X29582D01*
Y93894D01*
X29570D01*
Y93883D01*
X29559D01*
Y93871D01*
X29547D01*
Y93848D01*
X29536D01*
Y93837D01*
X29524D01*
Y93860D01*
X29536D01*
Y93883D01*
X29547D01*
Y93894D01*
X29559D01*
Y93917D01*
X29547D01*
Y93929D01*
X29559D01*
Y93940D01*
X29570D01*
Y93952D01*
X29582D01*
Y93963D01*
X29593D01*
Y93986D01*
X29605D01*
Y93998D01*
X29616D01*
Y94010D01*
X29628D01*
Y94021D01*
X29616D01*
Y94033D01*
X29639D01*
Y94067D01*
X29651D01*
Y94090D01*
X29662D01*
Y94102D01*
X29674D01*
Y94136D01*
X29685D01*
Y94148D01*
X29697D01*
Y94171D01*
X29708D01*
Y94182D01*
X29720D01*
Y94194D01*
X29732D01*
Y94205D01*
X29743D01*
Y94228D01*
X29754D01*
Y94240D01*
X29766D01*
Y94251D01*
X29789D01*
Y94286D01*
X29801D01*
Y94297D01*
X29824D01*
Y94320D01*
X29835D01*
Y94343D01*
X29858D01*
Y94355D01*
X29870D01*
Y94389D01*
X29881D01*
Y94412D01*
X29893D01*
Y94424D01*
X29904D01*
Y94412D01*
X29916D01*
Y94424D01*
X29927D01*
Y94436D01*
X29916D01*
Y94447D01*
X29927D01*
Y94459D01*
X29950D01*
Y94482D01*
X29962D01*
Y94505D01*
X29973D01*
Y94516D01*
X30008D01*
Y94551D01*
X30019D01*
Y94585D01*
X30031D01*
Y94597D01*
X30042D01*
Y94608D01*
X30054D01*
Y94631D01*
X30065D01*
Y94643D01*
X30077D01*
Y94654D01*
X30088D01*
Y94666D01*
X30100D01*
Y94677D01*
X30112D01*
Y94689D01*
X30123D01*
Y94700D01*
X30135D01*
Y94723D01*
X30146D01*
Y94735D01*
X30158D01*
Y94747D01*
X30169D01*
Y94758D01*
X30181D01*
Y94770D01*
X30192D01*
Y94804D01*
X30204D01*
Y94816D01*
X30215D01*
Y94827D01*
X30227D01*
Y94839D01*
X30238D01*
Y94850D01*
X30250D01*
Y94873D01*
X30261D01*
Y94885D01*
X30273D01*
Y94896D01*
X30284D01*
Y94908D01*
X30296D01*
Y94919D01*
X30319D01*
Y94908D01*
X30307D01*
Y94873D01*
X30296D01*
Y94862D01*
X30330D01*
Y94873D01*
X30353D01*
Y94885D01*
X30365D01*
Y94896D01*
X30376D01*
Y94908D01*
X30388D01*
Y94919D01*
X30399D01*
Y94896D01*
D02*
G37*
G36*
X27278Y94827D02*
Y94816D01*
X27267D01*
Y94839D01*
X27278D01*
Y94827D01*
D02*
G37*
G36*
X27394Y94723D02*
X27371D01*
Y94735D01*
X27394D01*
Y94723D01*
D02*
G37*
G36*
X27647Y94712D02*
X27635D01*
Y94723D01*
X27647D01*
Y94712D01*
D02*
G37*
G36*
X29167Y94700D02*
X29156D01*
Y94712D01*
X29167D01*
Y94700D01*
D02*
G37*
G36*
X27325D02*
X27313D01*
Y94712D01*
X27301D01*
Y94723D01*
X27313D01*
Y94735D01*
X27325D01*
Y94700D01*
D02*
G37*
G36*
X27140Y94735D02*
X27152D01*
Y94700D01*
X27140D01*
Y94712D01*
X27129D01*
Y94723D01*
Y94735D01*
Y94770D01*
X27117D01*
Y94793D01*
X27140D01*
Y94735D01*
D02*
G37*
G36*
X27348Y94723D02*
X27359D01*
Y94689D01*
X27348D01*
Y94700D01*
X27336D01*
Y94758D01*
X27348D01*
Y94723D01*
D02*
G37*
G36*
X29190Y94712D02*
X29202D01*
Y94677D01*
X29190D01*
Y94666D01*
X29179D01*
Y94689D01*
Y94700D01*
Y94723D01*
X29190D01*
Y94712D01*
D02*
G37*
G36*
X27670Y94654D02*
X27647D01*
Y94643D01*
X27624D01*
Y94654D01*
X27635D01*
Y94666D01*
X27670D01*
Y94654D01*
D02*
G37*
G36*
X26956D02*
Y94631D01*
X26945D01*
Y94643D01*
X26933D01*
Y94666D01*
X26956D01*
Y94654D01*
D02*
G37*
G36*
X30342Y94631D02*
X30319D01*
Y94620D01*
X30307D01*
Y94631D01*
X30296D01*
Y94643D01*
X30342D01*
Y94631D01*
D02*
G37*
G36*
X30296Y94597D02*
X30284D01*
Y94585D01*
X30273D01*
Y94597D01*
X30261D01*
Y94608D01*
X30273D01*
Y94620D01*
X30296D01*
Y94597D01*
D02*
G37*
G36*
X30261Y94562D02*
X30250D01*
Y94551D01*
X30238D01*
Y94562D01*
Y94574D01*
X30261D01*
Y94562D01*
D02*
G37*
G36*
X26910Y94528D02*
X26898D01*
Y94539D01*
Y94551D01*
X26910D01*
Y94528D01*
D02*
G37*
G36*
X30181Y94482D02*
X30169D01*
Y94493D01*
X30181D01*
Y94482D01*
D02*
G37*
G36*
X26875D02*
X26910D01*
Y94470D01*
X26921D01*
Y94424D01*
X26933D01*
Y94412D01*
X26945D01*
Y94389D01*
X26933D01*
Y94378D01*
X26910D01*
Y94389D01*
X26887D01*
Y94436D01*
Y94447D01*
X26875D01*
Y94459D01*
X26864D01*
Y94493D01*
X26875D01*
Y94482D01*
D02*
G37*
G36*
X26933Y94332D02*
X26910D01*
Y94355D01*
X26933D01*
Y94332D01*
D02*
G37*
G36*
X26898Y94309D02*
X26887D01*
Y94320D01*
X26898D01*
Y94309D01*
D02*
G37*
G36*
X26806Y94286D02*
X26795D01*
Y94297D01*
Y94309D01*
X26806D01*
Y94286D01*
D02*
G37*
G36*
X26818Y94240D02*
X26795D01*
Y94251D01*
Y94263D01*
X26818D01*
Y94240D01*
D02*
G37*
G36*
X27762Y94217D02*
X27751D01*
Y94228D01*
X27762D01*
Y94217D01*
D02*
G37*
G36*
X26829Y94182D02*
X26818D01*
Y94205D01*
X26829D01*
Y94182D01*
D02*
G37*
G36*
X26541Y94217D02*
X26553D01*
Y94171D01*
X26541D01*
Y94205D01*
Y94217D01*
X26530D01*
Y94228D01*
X26541D01*
Y94217D01*
D02*
G37*
G36*
X29282Y94113D02*
X29271D01*
Y94125D01*
X29282D01*
Y94113D01*
D02*
G37*
G36*
X29639Y93860D02*
X29628D01*
Y93871D01*
X29616D01*
Y93883D01*
Y93894D01*
X29639D01*
Y93860D01*
D02*
G37*
G36*
X29513Y93825D02*
Y93814D01*
X29490D01*
Y93825D01*
X29501D01*
Y93837D01*
X29513D01*
Y93825D01*
D02*
G37*
G36*
Y93779D02*
X29501D01*
Y93791D01*
X29513D01*
Y93779D01*
D02*
G37*
G36*
X29490D02*
X29501D01*
Y93756D01*
X29490D01*
Y93779D01*
X29467D01*
Y93768D01*
X29455D01*
Y93791D01*
X29467D01*
Y93802D01*
X29490D01*
Y93779D01*
D02*
G37*
G36*
X29305Y93756D02*
X29294D01*
Y93768D01*
X29305D01*
Y93756D01*
D02*
G37*
G36*
X29490Y93733D02*
X29478D01*
Y93745D01*
X29490D01*
Y93733D01*
D02*
G37*
G36*
X29455D02*
X29444D01*
Y93745D01*
X29455D01*
Y93733D01*
D02*
G37*
G36*
X29444Y93722D02*
X29421D01*
Y93733D01*
X29444D01*
Y93722D01*
D02*
G37*
G36*
X29421Y93687D02*
X29409D01*
Y93676D01*
X29397D01*
Y93687D01*
Y93699D01*
X29421D01*
Y93687D01*
D02*
G37*
G36*
X29375Y93676D02*
X29351D01*
Y93687D01*
X29363D01*
Y93699D01*
X29375D01*
Y93676D01*
D02*
G37*
G36*
X29317Y93699D02*
Y93676D01*
X29305D01*
Y93710D01*
X29317D01*
Y93699D01*
D02*
G37*
G36*
X30584Y93445D02*
D01*
D01*
D01*
D01*
D02*
G37*
G36*
X30388Y92604D02*
X30376D01*
Y92628D01*
X30388D01*
Y92604D01*
D02*
G37*
G36*
X28246Y92305D02*
X28234D01*
Y92317D01*
X28246D01*
Y92305D01*
D02*
G37*
G36*
X30296Y92259D02*
Y92247D01*
Y92224D01*
X30284D01*
Y92213D01*
X30273D01*
Y92247D01*
X30284D01*
Y92282D01*
X30296D01*
Y92259D01*
D02*
G37*
G36*
X28154Y92178D02*
X28131D01*
Y92190D01*
X28154D01*
Y92178D01*
D02*
G37*
G36*
X28292Y92098D02*
X28280D01*
Y92086D01*
X28269D01*
Y92109D01*
X28280D01*
Y92121D01*
X28292D01*
Y92098D01*
D02*
G37*
G36*
X28269Y92075D02*
X28257D01*
Y92063D01*
X28246D01*
Y92052D01*
X28223D01*
Y92063D01*
X28234D01*
Y92075D01*
X28246D01*
Y92086D01*
X28269D01*
Y92075D01*
D02*
G37*
G36*
X28131Y92144D02*
X28142D01*
Y92155D01*
X28177D01*
Y92132D01*
X28142D01*
Y92109D01*
X28154D01*
Y92086D01*
X28119D01*
Y92052D01*
X28096D01*
Y92040D01*
X28073D01*
Y92017D01*
X28050D01*
Y92029D01*
X28027D01*
Y92040D01*
X28050D01*
Y92052D01*
X28062D01*
Y92063D01*
X28050D01*
Y92075D01*
X28038D01*
Y92063D01*
X28016D01*
Y92075D01*
X28027D01*
Y92086D01*
X28038D01*
Y92098D01*
X28050D01*
Y92109D01*
X28062D01*
Y92121D01*
X28073D01*
Y92132D01*
X28085D01*
Y92144D01*
X28096D01*
Y92155D01*
X28108D01*
Y92167D01*
X28119D01*
Y92178D01*
X28131D01*
Y92144D01*
D02*
G37*
G36*
X28223Y92017D02*
X28211D01*
Y92006D01*
X28188D01*
Y92017D01*
X28200D01*
Y92029D01*
X28211D01*
Y92040D01*
X28223D01*
Y92017D01*
D02*
G37*
G36*
X28027Y92006D02*
X28038D01*
Y91994D01*
X28016D01*
Y91983D01*
X28004D01*
Y91994D01*
X27992D01*
Y92006D01*
X28004D01*
Y92017D01*
X28027D01*
Y92006D01*
D02*
G37*
G36*
X32472Y91430D02*
X32449D01*
Y91441D01*
X32472D01*
Y91430D01*
D02*
G37*
G36*
X32530Y91407D02*
X32507D01*
Y91418D01*
X32530D01*
Y91407D01*
D02*
G37*
G36*
X32438D02*
X32461D01*
Y91395D01*
X32472D01*
Y91384D01*
X32415D01*
Y91418D01*
X32392D01*
Y91430D01*
X32438D01*
Y91407D01*
D02*
G37*
G36*
X32380Y91395D02*
X32403D01*
Y91384D01*
X32415D01*
Y91361D01*
X32403D01*
Y91349D01*
X32392D01*
Y91338D01*
X32380D01*
Y91326D01*
X32369D01*
Y91315D01*
X32357D01*
Y91303D01*
X32346D01*
Y91326D01*
X32357D01*
Y91338D01*
X32369D01*
Y91349D01*
X32380D01*
Y91372D01*
X32311D01*
Y91361D01*
X32288D01*
Y91395D01*
X32311D01*
Y91384D01*
X32357D01*
Y91395D01*
X32346D01*
Y91418D01*
X32380D01*
Y91395D01*
D02*
G37*
G36*
X32254Y91372D02*
X32219D01*
Y91384D01*
X32254D01*
Y91372D01*
D02*
G37*
G36*
X31804Y91361D02*
X31770D01*
Y91372D01*
X31804D01*
Y91361D01*
D02*
G37*
G36*
X32438Y91349D02*
X32426D01*
Y91361D01*
X32438D01*
Y91349D01*
D02*
G37*
G36*
X32265Y91338D02*
X32242D01*
Y91349D01*
X32265D01*
Y91338D01*
D02*
G37*
G36*
X32184Y91372D02*
X32219D01*
Y91361D01*
X32162D01*
Y91349D01*
X32150D01*
Y91338D01*
X32104D01*
Y91349D01*
Y91361D01*
X32115D01*
Y91372D01*
X32173D01*
Y91384D01*
X32184D01*
Y91372D01*
D02*
G37*
G36*
X32069Y91326D02*
X32035D01*
Y91338D01*
X32069D01*
Y91326D01*
D02*
G37*
G36*
X31989Y91315D02*
X31931D01*
Y91326D01*
X31989D01*
Y91315D01*
D02*
G37*
G36*
X32449Y91292D02*
X32438D01*
Y91303D01*
X32449D01*
Y91292D01*
D02*
G37*
G36*
X31828D02*
X31770D01*
Y91303D01*
X31828D01*
Y91292D01*
D02*
G37*
G36*
X31275D02*
X31252D01*
Y91303D01*
X31275D01*
Y91292D01*
D02*
G37*
G36*
X32392D02*
Y91280D01*
X32369D01*
Y91303D01*
X32392D01*
Y91292D01*
D02*
G37*
G36*
X32334Y91280D02*
X32323D01*
Y91292D01*
X32334D01*
Y91280D01*
D02*
G37*
G36*
X32323Y91268D02*
X32311D01*
Y91280D01*
X32323D01*
Y91268D01*
D02*
G37*
G36*
X32277D02*
X32254D01*
Y91280D01*
X32277D01*
Y91268D01*
D02*
G37*
G36*
X32634Y91246D02*
X32622D01*
Y91257D01*
X32634D01*
Y91246D01*
D02*
G37*
G36*
X31793D02*
X31781D01*
Y91234D01*
X31735D01*
Y91223D01*
X31666D01*
Y91188D01*
X31758D01*
Y91176D01*
X31620D01*
Y91165D01*
X31609D01*
Y91153D01*
X31505D01*
Y91142D01*
X31471D01*
Y91130D01*
X31367D01*
Y91142D01*
X31378D01*
Y91153D01*
X31401D01*
Y91176D01*
X31378D01*
Y91188D01*
X31436D01*
Y91176D01*
X31447D01*
Y91165D01*
X31471D01*
Y91176D01*
X31482D01*
Y91199D01*
X31517D01*
Y91188D01*
X31528D01*
Y91176D01*
X31563D01*
Y91165D01*
X31574D01*
Y91176D01*
X31586D01*
Y91188D01*
X31574D01*
Y91211D01*
X31597D01*
Y91223D01*
X31609D01*
Y91234D01*
X31643D01*
Y91246D01*
X31678D01*
Y91234D01*
X31701D01*
Y91257D01*
X31735D01*
Y91246D01*
X31747D01*
Y91257D01*
X31793D01*
Y91246D01*
D02*
G37*
G36*
X31632Y91268D02*
X31586D01*
Y91257D01*
X31563D01*
Y91246D01*
X31528D01*
Y91234D01*
X31459D01*
Y91223D01*
X31390D01*
Y91234D01*
X31367D01*
Y91223D01*
X31159D01*
Y91211D01*
X31079D01*
Y91199D01*
X31044D01*
Y91188D01*
X31021D01*
Y91199D01*
X30998D01*
Y91188D01*
X30906D01*
Y91176D01*
X30872D01*
Y91188D01*
X30860D01*
Y91199D01*
X30745D01*
Y91188D01*
X30710D01*
Y91199D01*
X30733D01*
Y91211D01*
X30779D01*
Y91223D01*
X30803D01*
Y91234D01*
X30837D01*
Y91223D01*
X30849D01*
Y91211D01*
X30906D01*
Y91199D01*
X30918D01*
Y91223D01*
X30906D01*
Y91246D01*
X31010D01*
Y91234D01*
X31090D01*
Y91246D01*
X31079D01*
Y91257D01*
X31159D01*
Y91268D01*
X31171D01*
Y91257D01*
X31206D01*
Y91268D01*
X31217D01*
Y91280D01*
X31309D01*
Y91268D01*
X31275D01*
Y91246D01*
X31332D01*
Y91257D01*
X31471D01*
Y91268D01*
X31493D01*
Y91280D01*
X31632D01*
Y91268D01*
D02*
G37*
G36*
X32288Y91234D02*
X32277D01*
Y91246D01*
X32288D01*
Y91234D01*
D02*
G37*
G36*
X32622D02*
X32611D01*
Y91223D01*
X32599D01*
Y91234D01*
X32576D01*
Y91223D01*
X32507D01*
Y91211D01*
X32495D01*
Y91199D01*
X32449D01*
Y91223D01*
X32461D01*
Y91234D01*
X32553D01*
Y91246D01*
X32622D01*
Y91234D01*
D02*
G37*
G36*
X31574Y91223D02*
X31540D01*
Y91234D01*
X31574D01*
Y91223D01*
D02*
G37*
G36*
X30653Y91199D02*
X30676D01*
Y91188D01*
X30630D01*
Y91199D01*
X30618D01*
Y91211D01*
X30653D01*
Y91199D01*
D02*
G37*
G36*
X31816Y91188D02*
X31804D01*
Y91176D01*
X31770D01*
Y91188D01*
X31758D01*
Y91199D01*
X31816D01*
Y91188D01*
D02*
G37*
G36*
X30710Y91176D02*
X30687D01*
Y91188D01*
X30710D01*
Y91176D01*
D02*
G37*
G36*
X31286Y91153D02*
X31298D01*
Y91142D01*
X31275D01*
Y91153D01*
Y91165D01*
X31286D01*
Y91153D01*
D02*
G37*
G36*
X31148Y91142D02*
X31137D01*
Y91153D01*
X31148D01*
Y91142D01*
D02*
G37*
G36*
X30572Y91165D02*
X30584D01*
Y91142D01*
X30492D01*
Y91153D01*
X30538D01*
Y91165D01*
X30549D01*
Y91176D01*
X30572D01*
Y91165D01*
D02*
G37*
G36*
X30468Y91130D02*
X30434D01*
Y91142D01*
X30468D01*
Y91130D01*
D02*
G37*
G36*
X30422Y91165D02*
X30434D01*
Y91153D01*
X30399D01*
Y91142D01*
X30307D01*
Y91130D01*
X30261D01*
Y91142D01*
X30238D01*
Y91130D01*
X30158D01*
Y91119D01*
X30123D01*
Y91142D01*
X30204D01*
Y91153D01*
X30307D01*
Y91165D01*
X30353D01*
Y91176D01*
X30422D01*
Y91165D01*
D02*
G37*
G36*
X31850Y91107D02*
X31839D01*
Y91119D01*
Y91130D01*
X31850D01*
Y91107D01*
D02*
G37*
G36*
X30699Y91119D02*
Y91107D01*
X30687D01*
Y91130D01*
X30699D01*
Y91119D01*
D02*
G37*
G36*
X30365Y91107D02*
X30330D01*
Y91119D01*
X30353D01*
Y91130D01*
X30365D01*
Y91107D01*
D02*
G37*
G36*
X30273Y91096D02*
X30227D01*
Y91107D01*
X30273D01*
Y91096D01*
D02*
G37*
G36*
X30088Y91119D02*
X30112D01*
Y91107D01*
Y91084D01*
X30100D01*
Y91096D01*
X30054D01*
Y91107D01*
X30065D01*
Y91119D01*
X30077D01*
Y91130D01*
X30088D01*
Y91119D01*
D02*
G37*
G36*
X30031Y91084D02*
X30008D01*
Y91096D01*
X30031D01*
Y91084D01*
D02*
G37*
G36*
X29985D02*
X29962D01*
Y91096D01*
X29985D01*
Y91084D01*
D02*
G37*
G36*
X30181Y91073D02*
X30158D01*
Y91084D01*
X30146D01*
Y91096D01*
X30181D01*
Y91073D01*
D02*
G37*
G36*
X32104Y91084D02*
X32115D01*
Y91073D01*
X32104D01*
Y91061D01*
X32081D01*
Y91073D01*
X32069D01*
Y91084D01*
X32092D01*
Y91096D01*
X32104D01*
Y91084D01*
D02*
G37*
G36*
X32000Y91073D02*
X31989D01*
Y91061D01*
X31966D01*
Y91084D01*
X32000D01*
Y91073D01*
D02*
G37*
G36*
X30284Y91061D02*
X30261D01*
Y91084D01*
X30284D01*
Y91061D01*
D02*
G37*
G36*
X30065Y91073D02*
X30077D01*
Y91061D01*
X30042D01*
Y91084D01*
X30065D01*
Y91073D01*
D02*
G37*
G36*
X29996Y91050D02*
X29985D01*
Y91061D01*
X29996D01*
Y91050D01*
D02*
G37*
G36*
X31885Y91073D02*
X31931D01*
Y91050D01*
X31943D01*
Y91038D01*
X31897D01*
Y91050D01*
X31885D01*
Y91061D01*
X31850D01*
Y91050D01*
X31839D01*
Y91061D01*
X31828D01*
Y91073D01*
X31839D01*
Y91084D01*
X31885D01*
Y91073D01*
D02*
G37*
G36*
X30042Y91027D02*
X30031D01*
Y91038D01*
X30042D01*
Y91027D01*
D02*
G37*
G36*
X31989D02*
X31977D01*
Y91015D01*
X31966D01*
Y91038D01*
X31989D01*
Y91027D01*
D02*
G37*
G36*
X30123Y91038D02*
X30112D01*
Y91027D01*
X30100D01*
Y91015D01*
X30088D01*
Y91027D01*
X30077D01*
Y91038D01*
X30100D01*
Y91050D01*
X30123D01*
Y91038D01*
D02*
G37*
G36*
X30284Y90992D02*
X30261D01*
Y91004D01*
X30284D01*
Y90992D01*
D02*
G37*
G36*
X30227Y90981D02*
Y90969D01*
X30215D01*
Y90981D01*
X30204D01*
Y90992D01*
X30227D01*
Y90981D01*
D02*
G37*
G36*
Y90912D02*
X30192D01*
Y90923D01*
X30227D01*
Y90912D01*
D02*
G37*
G36*
X30135D02*
X30123D01*
Y90900D01*
X30100D01*
Y90912D01*
X30112D01*
Y90923D01*
X30135D01*
Y90912D01*
D02*
G37*
G36*
X30388Y90889D02*
X30330D01*
Y90900D01*
X30342D01*
Y90912D01*
X30388D01*
Y90889D01*
D02*
G37*
G36*
X30261Y90900D02*
X30273D01*
Y90889D01*
X30250D01*
Y90912D01*
X30261D01*
Y90900D01*
D02*
G37*
G36*
X32645Y90831D02*
X32634D01*
Y90819D01*
X32622D01*
Y90831D01*
Y90842D01*
X32645D01*
Y90831D01*
D02*
G37*
G36*
X26334Y90531D02*
X26323D01*
Y90520D01*
X26311D01*
Y90497D01*
X26300D01*
Y90485D01*
X26288D01*
Y90474D01*
X26265D01*
Y90462D01*
X26242D01*
Y90474D01*
X26254D01*
Y90497D01*
X26276D01*
Y90508D01*
X26288D01*
Y90531D01*
X26300D01*
Y90543D01*
X26334D01*
Y90531D01*
D02*
G37*
G36*
X32576Y90439D02*
X32553D01*
Y90451D01*
X32576D01*
Y90439D01*
D02*
G37*
G36*
X32530Y90382D02*
X32507D01*
Y90393D01*
X32519D01*
Y90405D01*
X32530D01*
Y90382D01*
D02*
G37*
G36*
X32495Y90301D02*
X32484D01*
Y90313D01*
X32495D01*
Y90301D01*
D02*
G37*
G36*
X32369Y90163D02*
D01*
D01*
D01*
D01*
D02*
G37*
G36*
X32380Y90117D02*
D01*
D01*
D01*
D01*
D02*
G37*
G36*
X32369Y90036D02*
X32357D01*
Y90025D01*
X32346D01*
Y90048D01*
X32369D01*
Y90036D01*
D02*
G37*
G36*
X26046Y90025D02*
X26023D01*
Y90036D01*
X26035D01*
Y90048D01*
X26046D01*
Y90025D01*
D02*
G37*
G36*
X26023Y90013D02*
X26012D01*
Y90025D01*
X26023D01*
Y90013D01*
D02*
G37*
G36*
X25885D02*
X25896D01*
Y90002D01*
X25873D01*
Y90025D01*
X25885D01*
Y90013D01*
D02*
G37*
G36*
X25919Y89956D02*
X25908D01*
Y89967D01*
X25919D01*
Y89956D01*
D02*
G37*
G36*
X25931Y89817D02*
X25919D01*
Y89829D01*
X25931D01*
Y89817D01*
D02*
G37*
G36*
X25966Y89806D02*
X25954D01*
Y89817D01*
X25966D01*
Y89806D01*
D02*
G37*
G36*
X25747Y89794D02*
X25735D01*
Y89783D01*
X25724D01*
Y89806D01*
X25735D01*
Y89817D01*
X25747D01*
Y89794D01*
D02*
G37*
G36*
X25885Y89771D02*
X25873D01*
Y89783D01*
X25885D01*
Y89771D01*
D02*
G37*
G36*
X25701Y89760D02*
X25689D01*
Y89771D01*
X25701D01*
Y89760D01*
D02*
G37*
G36*
X25747Y89668D02*
X25735D01*
Y89656D01*
X25724D01*
Y89633D01*
X25689D01*
Y89656D01*
X25701D01*
Y89668D01*
X25712D01*
Y89679D01*
X25735D01*
Y89691D01*
X25747D01*
Y89668D01*
D02*
G37*
G36*
X25689Y89622D02*
X25666D01*
Y89633D01*
X25689D01*
Y89622D01*
D02*
G37*
G36*
X31989Y89426D02*
X31977D01*
Y89449D01*
X31989D01*
Y89426D01*
D02*
G37*
G36*
X25505Y89299D02*
X25493D01*
Y89311D01*
X25505D01*
Y89299D01*
D02*
G37*
G36*
X25367Y89115D02*
X25355D01*
Y89103D01*
X25344D01*
Y89092D01*
X25332D01*
Y89115D01*
X25344D01*
Y89126D01*
X25355D01*
Y89138D01*
X25367D01*
Y89115D01*
D02*
G37*
G36*
X25563Y88654D02*
X25551D01*
Y88666D01*
X25563D01*
Y88654D01*
D02*
G37*
G36*
X137058Y92643D02*
X137166D01*
Y92589D01*
X137274D01*
Y92535D01*
X137328D01*
Y92481D01*
Y92427D01*
X137382D01*
Y92373D01*
Y92319D01*
X137436D01*
Y92265D01*
Y92211D01*
Y92157D01*
Y92102D01*
Y92048D01*
Y91994D01*
Y91940D01*
Y91886D01*
Y91832D01*
Y91778D01*
Y91724D01*
Y91670D01*
Y91616D01*
Y91562D01*
Y91508D01*
Y91454D01*
Y91400D01*
Y91346D01*
Y91292D01*
Y91237D01*
Y91183D01*
Y91129D01*
Y91075D01*
Y91021D01*
Y90967D01*
Y90913D01*
Y90859D01*
Y90805D01*
Y90751D01*
Y90697D01*
Y90643D01*
Y90589D01*
Y90535D01*
Y90481D01*
Y90427D01*
Y90373D01*
Y90318D01*
Y90264D01*
Y90210D01*
Y90156D01*
Y90102D01*
Y90048D01*
Y89994D01*
Y89940D01*
Y89886D01*
Y89832D01*
Y89778D01*
Y89724D01*
Y89670D01*
Y89616D01*
Y89562D01*
Y89508D01*
Y89453D01*
Y89399D01*
Y89345D01*
Y89291D01*
Y89237D01*
Y89183D01*
Y89129D01*
Y89075D01*
Y89021D01*
Y88967D01*
Y88913D01*
Y88859D01*
Y88805D01*
Y88751D01*
Y88697D01*
Y88643D01*
Y88589D01*
Y88534D01*
Y88480D01*
Y88426D01*
Y88372D01*
Y88318D01*
Y88264D01*
Y88210D01*
Y88156D01*
Y88102D01*
Y88048D01*
Y87994D01*
Y87940D01*
Y87886D01*
Y87832D01*
Y87778D01*
Y87723D01*
Y87669D01*
Y87615D01*
Y87561D01*
Y87507D01*
Y87453D01*
Y87399D01*
Y87345D01*
Y87291D01*
Y87237D01*
Y87183D01*
Y87129D01*
Y87075D01*
Y87021D01*
Y86967D01*
X137490D01*
Y86913D01*
Y86858D01*
X137544D01*
Y86804D01*
X137598D01*
Y86750D01*
X137652D01*
Y86696D01*
X137760D01*
Y86642D01*
X176685D01*
Y86588D01*
X176901D01*
Y86534D01*
X177064D01*
Y86480D01*
X177172D01*
Y86426D01*
X177280D01*
Y86372D01*
X177388D01*
Y86318D01*
X177496D01*
Y86264D01*
X177550D01*
Y86210D01*
X177658D01*
Y86156D01*
X177712D01*
Y86102D01*
X177766D01*
Y86048D01*
X177874D01*
Y85993D01*
X177928D01*
Y85939D01*
X177982D01*
Y85885D01*
X178037D01*
Y85831D01*
X178091D01*
Y85777D01*
X178145D01*
Y85723D01*
X178199D01*
Y85669D01*
X178253D01*
Y85615D01*
X178307D01*
Y85561D01*
X178361D01*
Y85507D01*
X178415D01*
Y85453D01*
Y85399D01*
X178469D01*
Y85345D01*
X178523D01*
Y85291D01*
X178577D01*
Y85237D01*
Y85183D01*
X178631D01*
Y85128D01*
X178685D01*
Y85074D01*
Y85020D01*
X178739D01*
Y84966D01*
X178794D01*
Y84912D01*
Y84858D01*
X178848D01*
Y84804D01*
Y84750D01*
X178902D01*
Y84696D01*
Y84642D01*
X178956D01*
Y84588D01*
Y84534D01*
Y84480D01*
X179010D01*
Y84426D01*
Y84372D01*
Y84318D01*
X179064D01*
Y84263D01*
Y84209D01*
Y84155D01*
X179118D01*
Y84101D01*
Y84047D01*
Y83993D01*
X179172D01*
Y83939D01*
Y83885D01*
Y83831D01*
Y83777D01*
Y83723D01*
X179226D01*
Y83669D01*
Y83615D01*
Y83561D01*
Y83507D01*
Y83453D01*
Y83398D01*
Y83344D01*
Y83290D01*
Y83236D01*
Y83182D01*
X179280D01*
Y83128D01*
Y83074D01*
X179226D01*
Y83020D01*
Y82966D01*
Y82912D01*
Y82858D01*
Y82804D01*
Y82750D01*
Y82696D01*
Y82642D01*
Y82588D01*
X179172D01*
Y82534D01*
Y82479D01*
Y82425D01*
Y82371D01*
Y82317D01*
Y82263D01*
X179118D01*
Y82209D01*
Y82155D01*
Y82101D01*
X179064D01*
Y82047D01*
Y81993D01*
Y81939D01*
X179010D01*
Y81885D01*
Y81831D01*
Y81777D01*
X178956D01*
Y81723D01*
Y81669D01*
X178902D01*
Y81615D01*
Y81560D01*
X178848D01*
Y81506D01*
Y81452D01*
X178794D01*
Y81398D01*
Y81344D01*
X178739D01*
Y81290D01*
X178685D01*
Y81236D01*
Y81182D01*
X178631D01*
Y81128D01*
X178577D01*
Y81074D01*
Y81020D01*
X178523D01*
Y80966D01*
X178469D01*
Y80912D01*
X178415D01*
Y80858D01*
X178361D01*
Y80804D01*
Y80749D01*
X178307D01*
Y80695D01*
X178253D01*
Y80641D01*
X178199D01*
Y80587D01*
X178145D01*
Y80533D01*
X178091D01*
Y80479D01*
X177982D01*
Y80425D01*
X177928D01*
Y80371D01*
X177874D01*
Y80317D01*
X177820D01*
Y80263D01*
X177712D01*
Y80209D01*
X177658D01*
Y80155D01*
X177550D01*
Y80101D01*
X177442D01*
Y80047D01*
X177388D01*
Y79993D01*
X177280D01*
Y79939D01*
X177172D01*
Y79884D01*
X177009D01*
Y79830D01*
X176847D01*
Y79776D01*
X176685D01*
Y79722D01*
X176523D01*
Y79668D01*
X176253D01*
Y79614D01*
X165062D01*
Y79560D01*
X164575D01*
Y79506D01*
X164305D01*
Y79452D01*
X164089D01*
Y79398D01*
X163980D01*
Y79344D01*
X163818D01*
Y79290D01*
X163710D01*
Y79236D01*
X163602D01*
Y79182D01*
X163494D01*
Y79128D01*
X163386D01*
Y79074D01*
X163278D01*
Y79019D01*
X163224D01*
Y78965D01*
X163116D01*
Y78911D01*
X163061D01*
Y78857D01*
X163007D01*
Y78803D01*
X162899D01*
Y78749D01*
X162845D01*
Y78695D01*
X162791D01*
Y78641D01*
X162737D01*
Y78587D01*
X162683D01*
Y78533D01*
X162629D01*
Y78479D01*
X162575D01*
Y78425D01*
X162521D01*
Y78371D01*
X162467D01*
Y78317D01*
X162413D01*
Y78263D01*
Y78209D01*
X162359D01*
Y78154D01*
X162305D01*
Y78100D01*
X162250D01*
Y78046D01*
Y77992D01*
X162197D01*
Y77938D01*
X162142D01*
Y77884D01*
Y77830D01*
X162088D01*
Y77776D01*
Y77722D01*
X162034D01*
Y77668D01*
Y77614D01*
X161980D01*
Y77560D01*
Y77506D01*
X161926D01*
Y77452D01*
Y77398D01*
X161872D01*
Y77344D01*
Y77289D01*
Y77235D01*
X161818D01*
Y77181D01*
Y77127D01*
Y77073D01*
X161764D01*
Y77019D01*
Y76965D01*
Y76911D01*
X161710D01*
Y76857D01*
Y76803D01*
Y76749D01*
Y76695D01*
Y76641D01*
X161656D01*
Y76587D01*
Y76533D01*
Y76479D01*
Y76424D01*
Y76371D01*
Y76316D01*
Y76262D01*
Y76208D01*
Y76154D01*
Y76100D01*
Y76046D01*
Y75992D01*
Y75938D01*
Y75884D01*
Y75830D01*
Y75776D01*
Y75722D01*
Y75668D01*
Y75614D01*
Y75560D01*
Y75505D01*
X161710D01*
Y75451D01*
Y75397D01*
Y75343D01*
Y75289D01*
Y75235D01*
X161764D01*
Y75181D01*
Y75127D01*
Y75073D01*
X161818D01*
Y75019D01*
Y74965D01*
Y74911D01*
X161872D01*
Y74857D01*
Y74803D01*
Y74749D01*
X161926D01*
Y74695D01*
Y74641D01*
X161980D01*
Y74586D01*
Y74532D01*
X162034D01*
Y74478D01*
Y74424D01*
X162088D01*
Y74370D01*
Y74316D01*
X162142D01*
Y74262D01*
X162197D01*
Y74208D01*
Y74154D01*
X162250D01*
Y74100D01*
X162305D01*
Y74046D01*
Y73992D01*
X162359D01*
Y73938D01*
X162413D01*
Y73884D01*
X162467D01*
Y73830D01*
X162521D01*
Y73776D01*
Y73721D01*
X162575D01*
Y73667D01*
X162629D01*
Y73613D01*
X162683D01*
Y73559D01*
X162737D01*
Y73505D01*
X162791D01*
Y73451D01*
X162899D01*
Y73397D01*
X162953D01*
Y73343D01*
X163007D01*
Y73289D01*
X163061D01*
Y73235D01*
X163170D01*
Y73181D01*
X163224D01*
Y73127D01*
X163332D01*
Y73073D01*
X163440D01*
Y73019D01*
X163494D01*
Y72965D01*
X163602D01*
Y72910D01*
X163710D01*
Y72856D01*
X163872D01*
Y72802D01*
X163980D01*
Y72748D01*
X164143D01*
Y72694D01*
X164359D01*
Y72640D01*
X164629D01*
Y72586D01*
X165170D01*
Y72532D01*
X165224D01*
Y72586D01*
X181442D01*
Y72532D01*
X181497D01*
Y72586D01*
X181605D01*
Y72532D01*
X181983D01*
Y72478D01*
X182253D01*
Y72424D01*
X182416D01*
Y72370D01*
X182578D01*
Y72316D01*
X182740D01*
Y72262D01*
X182848D01*
Y72208D01*
X182956D01*
Y72154D01*
X183064D01*
Y72100D01*
X183173D01*
Y72045D01*
X183227D01*
Y71991D01*
X183335D01*
Y71937D01*
X183389D01*
Y71883D01*
X183497D01*
Y71829D01*
X183551D01*
Y71775D01*
X183605D01*
Y71721D01*
X183713D01*
Y71667D01*
X183767D01*
Y71613D01*
X183821D01*
Y71559D01*
X183875D01*
Y71505D01*
X183929D01*
Y71451D01*
X183983D01*
Y71397D01*
X184037D01*
Y71343D01*
X184092D01*
Y71289D01*
Y71235D01*
X184146D01*
Y71180D01*
X184200D01*
Y71126D01*
X184254D01*
Y71072D01*
X184308D01*
Y71018D01*
Y70964D01*
X184362D01*
Y70910D01*
X184416D01*
Y70856D01*
Y70802D01*
X184470D01*
Y70748D01*
Y70694D01*
X184524D01*
Y70640D01*
Y70586D01*
X184578D01*
Y70532D01*
Y70478D01*
X184632D01*
Y70424D01*
Y70370D01*
X184686D01*
Y70315D01*
Y70261D01*
Y70207D01*
X184740D01*
Y70153D01*
Y70099D01*
Y70045D01*
X184794D01*
Y69991D01*
Y69937D01*
Y69883D01*
X184848D01*
Y69829D01*
Y69775D01*
Y69721D01*
Y69667D01*
Y69613D01*
X184903D01*
Y69559D01*
Y69505D01*
Y69450D01*
Y69397D01*
Y69342D01*
Y69288D01*
Y69234D01*
Y69180D01*
Y69126D01*
Y69072D01*
Y69018D01*
Y68964D01*
Y68910D01*
Y68856D01*
Y68802D01*
Y68748D01*
Y68694D01*
Y68640D01*
Y68585D01*
Y68531D01*
Y68477D01*
X184848D01*
Y68423D01*
Y68369D01*
Y68315D01*
Y68261D01*
Y68207D01*
X184794D01*
Y68153D01*
Y68099D01*
Y68045D01*
Y67991D01*
X184740D01*
Y67937D01*
Y67883D01*
Y67829D01*
X184686D01*
Y67775D01*
Y67721D01*
X184632D01*
Y67667D01*
Y67612D01*
Y67558D01*
X184578D01*
Y67504D01*
Y67450D01*
X184524D01*
Y67396D01*
Y67342D01*
X184470D01*
Y67288D01*
X184416D01*
Y67234D01*
Y67180D01*
X184362D01*
Y67126D01*
Y67072D01*
X184308D01*
Y67018D01*
X184254D01*
Y66964D01*
X184200D01*
Y66910D01*
Y66856D01*
X184146D01*
Y66802D01*
X184092D01*
Y66747D01*
X184037D01*
Y66693D01*
X183983D01*
Y66639D01*
X183929D01*
Y66585D01*
X183875D01*
Y66531D01*
X183821D01*
Y66477D01*
X183767D01*
Y66423D01*
X183713D01*
Y66369D01*
X183659D01*
Y66315D01*
X183605D01*
Y66261D01*
X183497D01*
Y66207D01*
X183443D01*
Y66153D01*
X183389D01*
Y66099D01*
X183281D01*
Y66045D01*
X183227D01*
Y65991D01*
X183118D01*
Y65936D01*
X183010D01*
Y65882D01*
X182902D01*
Y65828D01*
X182794D01*
Y65774D01*
X182632D01*
Y65720D01*
X182470D01*
Y65666D01*
X182308D01*
Y65612D01*
X182091D01*
Y65558D01*
X181821D01*
Y65504D01*
X171441D01*
Y65450D01*
X171063D01*
Y65396D01*
X170846D01*
Y65342D01*
X170684D01*
Y65288D01*
X170522D01*
Y65234D01*
X170414D01*
Y65180D01*
X170252D01*
Y65126D01*
X170144D01*
Y65071D01*
X170089D01*
Y65017D01*
X169981D01*
Y64963D01*
X169873D01*
Y64909D01*
X169819D01*
Y64855D01*
X169711D01*
Y64801D01*
X169657D01*
Y64747D01*
X169603D01*
Y64693D01*
X169495D01*
Y64639D01*
X169441D01*
Y64585D01*
X169387D01*
Y64531D01*
X169333D01*
Y64477D01*
X169279D01*
Y64423D01*
X169225D01*
Y64369D01*
X169170D01*
Y64315D01*
X169116D01*
Y64261D01*
X169062D01*
Y64206D01*
X169008D01*
Y64152D01*
Y64098D01*
X168954D01*
Y64044D01*
X168900D01*
Y63990D01*
X168846D01*
Y63936D01*
Y63882D01*
X168792D01*
Y63828D01*
X168738D01*
Y63774D01*
Y63720D01*
X168684D01*
Y63666D01*
Y63612D01*
X168630D01*
Y63558D01*
Y63504D01*
X168576D01*
Y63450D01*
Y63396D01*
X168522D01*
Y63341D01*
Y63287D01*
X168468D01*
Y63233D01*
Y63179D01*
Y63125D01*
X168414D01*
Y63071D01*
Y63017D01*
Y62963D01*
X168359D01*
Y62909D01*
Y62855D01*
Y62801D01*
Y62747D01*
X168305D01*
Y62693D01*
Y62639D01*
Y62585D01*
Y62531D01*
Y62476D01*
Y62423D01*
X168251D01*
Y62368D01*
Y62314D01*
Y62260D01*
Y62206D01*
Y62152D01*
Y62098D01*
Y62044D01*
Y61990D01*
Y61936D01*
Y61882D01*
Y61828D01*
Y61774D01*
Y61720D01*
Y61666D01*
Y61611D01*
Y61557D01*
X168305D01*
Y61503D01*
Y61449D01*
Y61395D01*
Y61341D01*
Y61287D01*
Y61233D01*
X168359D01*
Y61179D01*
Y61125D01*
Y61071D01*
Y61017D01*
X168414D01*
Y60963D01*
Y60909D01*
Y60855D01*
X168468D01*
Y60801D01*
Y60747D01*
Y60693D01*
X168522D01*
Y60638D01*
Y60584D01*
X168576D01*
Y60530D01*
Y60476D01*
X168630D01*
Y60422D01*
Y60368D01*
X168684D01*
Y60314D01*
Y60260D01*
X168738D01*
Y60206D01*
Y60152D01*
X168792D01*
Y60098D01*
X168846D01*
Y60044D01*
Y59990D01*
X168900D01*
Y59936D01*
X168954D01*
Y59882D01*
Y59828D01*
X169008D01*
Y59773D01*
X169062D01*
Y59719D01*
X169116D01*
Y59665D01*
X169170D01*
Y59611D01*
X169225D01*
Y59557D01*
X169279D01*
Y59503D01*
X169333D01*
Y59449D01*
X169387D01*
Y59395D01*
X169441D01*
Y59341D01*
X169495D01*
Y59287D01*
X169549D01*
Y59233D01*
X169657D01*
Y59179D01*
X169711D01*
Y59125D01*
X169765D01*
Y59071D01*
X169873D01*
Y59017D01*
X169927D01*
Y58963D01*
X170035D01*
Y58908D01*
X170144D01*
Y58854D01*
X170252D01*
Y58800D01*
X170360D01*
Y58746D01*
X170522D01*
Y58692D01*
X170630D01*
Y58638D01*
X170846D01*
Y58584D01*
X171063D01*
Y58530D01*
X171387D01*
Y58476D01*
X199445D01*
Y58422D01*
X199770D01*
Y58368D01*
X199986D01*
Y58314D01*
X200148D01*
Y58260D01*
X200310D01*
Y58206D01*
X200418D01*
Y58152D01*
X200526D01*
Y58097D01*
X200689D01*
Y58043D01*
X200743D01*
Y57989D01*
X200851D01*
Y57935D01*
X200959D01*
Y57881D01*
X201013D01*
Y57827D01*
X201121D01*
Y57773D01*
X201175D01*
Y57719D01*
X201229D01*
Y57665D01*
X201337D01*
Y57611D01*
X201391D01*
Y57557D01*
X201446D01*
Y57503D01*
X201500D01*
Y57449D01*
X201554D01*
Y57395D01*
X201608D01*
Y57341D01*
X201662D01*
Y57287D01*
X201716D01*
Y57232D01*
X201770D01*
Y57178D01*
Y57124D01*
X201824D01*
Y57070D01*
X201878D01*
Y57016D01*
X201932D01*
Y56962D01*
X201986D01*
Y56908D01*
Y56854D01*
X202040D01*
Y56800D01*
X202094D01*
Y56746D01*
Y56692D01*
X202148D01*
Y56638D01*
Y56584D01*
X202202D01*
Y56530D01*
Y56476D01*
X202256D01*
Y56422D01*
Y56367D01*
X202310D01*
Y56313D01*
Y56259D01*
X202364D01*
Y56205D01*
Y56151D01*
Y56097D01*
X202419D01*
Y56043D01*
Y55989D01*
Y55935D01*
X202473D01*
Y55881D01*
Y55827D01*
Y55773D01*
Y55719D01*
X202527D01*
Y55665D01*
Y55611D01*
Y55557D01*
Y55502D01*
Y55449D01*
X202581D01*
Y55394D01*
Y55340D01*
Y55286D01*
Y55232D01*
Y55178D01*
Y55124D01*
Y55070D01*
Y55016D01*
Y54962D01*
Y54908D01*
Y54854D01*
Y54800D01*
Y54746D01*
Y54692D01*
Y54637D01*
Y54584D01*
Y54529D01*
Y54475D01*
Y54421D01*
X202527D01*
Y54367D01*
Y54313D01*
Y54259D01*
Y54205D01*
Y54151D01*
X202473D01*
Y54097D01*
Y54043D01*
Y53989D01*
Y53935D01*
X202419D01*
Y53881D01*
Y53827D01*
Y53772D01*
X202364D01*
Y53719D01*
Y53664D01*
X202310D01*
Y53610D01*
Y53556D01*
Y53502D01*
X202256D01*
Y53448D01*
Y53394D01*
X202202D01*
Y53340D01*
Y53286D01*
X202148D01*
Y53232D01*
Y53178D01*
X202094D01*
Y53124D01*
X202040D01*
Y53070D01*
Y53016D01*
X201986D01*
Y52962D01*
X201932D01*
Y52908D01*
Y52854D01*
X201878D01*
Y52799D01*
X201824D01*
Y52745D01*
X201770D01*
Y52691D01*
X201716D01*
Y52637D01*
Y52583D01*
X201662D01*
Y52529D01*
X201608D01*
Y52475D01*
X201554D01*
Y52421D01*
X201500D01*
Y52367D01*
X201446D01*
Y52313D01*
X201337D01*
Y52259D01*
X201283D01*
Y52205D01*
X201229D01*
Y52151D01*
X201175D01*
Y52097D01*
X201067D01*
Y52043D01*
X201013D01*
Y51989D01*
X200905D01*
Y51934D01*
X200851D01*
Y51880D01*
X200743D01*
Y51826D01*
X200635D01*
Y51772D01*
X200526D01*
Y51718D01*
X200418D01*
Y51664D01*
X200256D01*
Y51610D01*
X200094D01*
Y51556D01*
X199932D01*
Y51502D01*
X199715D01*
Y51448D01*
X199337D01*
Y51394D01*
X199283D01*
Y51448D01*
X199229D01*
Y51394D01*
X156466D01*
Y51340D01*
X156196D01*
Y51286D01*
X155979D01*
Y51232D01*
X155817D01*
Y51178D01*
X155655D01*
Y51123D01*
X155547D01*
Y51069D01*
X155439D01*
Y51015D01*
X155331D01*
Y50961D01*
X155222D01*
Y50907D01*
X155114D01*
Y50853D01*
X155060D01*
Y50799D01*
X154952D01*
Y50745D01*
X154898D01*
Y50691D01*
X154790D01*
Y50637D01*
X154736D01*
Y50583D01*
X154682D01*
Y50529D01*
X154628D01*
Y50475D01*
X154574D01*
Y50421D01*
X154520D01*
Y50367D01*
X154466D01*
Y50313D01*
X154411D01*
Y50258D01*
X154358D01*
Y50204D01*
X154303D01*
Y50150D01*
X154249D01*
Y50096D01*
X154195D01*
Y50042D01*
X154141D01*
Y49988D01*
Y49934D01*
X154087D01*
Y49880D01*
X154033D01*
Y49826D01*
Y49772D01*
X153979D01*
Y49718D01*
X153925D01*
Y49664D01*
Y49610D01*
X153871D01*
Y49556D01*
Y49502D01*
X153817D01*
Y49448D01*
Y49393D01*
X153763D01*
Y49339D01*
Y49285D01*
X153709D01*
Y49231D01*
Y49177D01*
X153655D01*
Y49123D01*
Y49069D01*
Y49015D01*
X153601D01*
Y48961D01*
Y48907D01*
Y48853D01*
X153547D01*
Y48799D01*
Y48745D01*
Y48691D01*
Y48637D01*
X153492D01*
Y48583D01*
Y48529D01*
Y48474D01*
Y48420D01*
Y48366D01*
Y48312D01*
X153438D01*
Y48258D01*
Y48204D01*
Y48150D01*
Y48096D01*
Y48042D01*
Y47988D01*
Y47934D01*
Y47880D01*
Y47826D01*
Y47772D01*
Y47718D01*
Y47664D01*
Y47609D01*
Y47555D01*
Y47501D01*
Y47447D01*
X153492D01*
Y47393D01*
Y47339D01*
Y47285D01*
Y47231D01*
Y47177D01*
Y47123D01*
X153547D01*
Y47069D01*
Y47015D01*
Y46961D01*
Y46907D01*
X153601D01*
Y46853D01*
Y46799D01*
Y46744D01*
X153655D01*
Y46690D01*
Y46636D01*
X153709D01*
Y46582D01*
Y46528D01*
Y46474D01*
X153763D01*
Y46420D01*
Y46366D01*
X153817D01*
Y46312D01*
Y46258D01*
X153871D01*
Y46204D01*
Y46150D01*
X153925D01*
Y46096D01*
X153979D01*
Y46042D01*
Y45988D01*
X154033D01*
Y45933D01*
X154087D01*
Y45880D01*
Y45825D01*
X154141D01*
Y45771D01*
X154195D01*
Y45717D01*
X154249D01*
Y45663D01*
Y45609D01*
X154303D01*
Y45555D01*
X154358D01*
Y45501D01*
X154411D01*
Y45447D01*
X154466D01*
Y45393D01*
X154520D01*
Y45339D01*
X154574D01*
Y45285D01*
X154628D01*
Y45231D01*
X154736D01*
Y45177D01*
X154790D01*
Y45123D01*
X154844D01*
Y45068D01*
X154898D01*
Y45015D01*
X155006D01*
Y44960D01*
X155114D01*
Y44906D01*
X155168D01*
Y44852D01*
X155277D01*
Y44798D01*
X155385D01*
Y44744D01*
X155493D01*
Y44690D01*
X155601D01*
Y44636D01*
X155763D01*
Y44582D01*
X155871D01*
Y44528D01*
X156087D01*
Y44474D01*
X156304D01*
Y44420D01*
X156736D01*
Y44366D01*
X164900D01*
Y44312D01*
X165224D01*
Y44258D01*
X165386D01*
Y44204D01*
X165602D01*
Y44150D01*
X165710D01*
Y44095D01*
X165873D01*
Y44041D01*
X165981D01*
Y43987D01*
X166089D01*
Y43933D01*
X166197D01*
Y43879D01*
X166251D01*
Y43825D01*
X166359D01*
Y43771D01*
X166413D01*
Y43717D01*
X166521D01*
Y43663D01*
X166576D01*
Y43609D01*
X166630D01*
Y43555D01*
X166738D01*
Y43501D01*
X166792D01*
Y43447D01*
X166846D01*
Y43393D01*
X166900D01*
Y43339D01*
X166954D01*
Y43284D01*
X167008D01*
Y43230D01*
X167062D01*
Y43176D01*
X167116D01*
Y43122D01*
X167170D01*
Y43068D01*
Y43014D01*
X167224D01*
Y42960D01*
X167278D01*
Y42906D01*
X167332D01*
Y42852D01*
Y42798D01*
X167386D01*
Y42744D01*
X167440D01*
Y42690D01*
Y42636D01*
X167494D01*
Y42582D01*
X167549D01*
Y42528D01*
Y42474D01*
X167603D01*
Y42419D01*
Y42365D01*
X167657D01*
Y42311D01*
Y42257D01*
X167711D01*
Y42203D01*
Y42149D01*
Y42095D01*
X167765D01*
Y42041D01*
Y41987D01*
Y41933D01*
X167819D01*
Y41879D01*
Y41825D01*
Y41771D01*
X167873D01*
Y41717D01*
Y41663D01*
Y41609D01*
Y41554D01*
X167927D01*
Y41500D01*
Y41446D01*
Y41392D01*
Y41338D01*
Y41284D01*
Y41230D01*
Y41176D01*
X167981D01*
Y41122D01*
X167927D01*
Y41068D01*
X167981D01*
Y41014D01*
Y40960D01*
Y40906D01*
Y40852D01*
Y40798D01*
Y40744D01*
Y40690D01*
Y40635D01*
Y40581D01*
Y40527D01*
Y40473D01*
X167927D01*
Y40419D01*
Y40365D01*
Y40311D01*
Y40257D01*
Y40203D01*
Y40149D01*
X167873D01*
Y40095D01*
Y40041D01*
Y39987D01*
Y39933D01*
X167819D01*
Y39879D01*
Y39825D01*
Y39770D01*
X167765D01*
Y39716D01*
Y39662D01*
Y39608D01*
X167711D01*
Y39554D01*
Y39500D01*
Y39446D01*
X167657D01*
Y39392D01*
Y39338D01*
X167603D01*
Y39284D01*
Y39230D01*
X167549D01*
Y39176D01*
Y39122D01*
X167494D01*
Y39068D01*
X167440D01*
Y39014D01*
Y38960D01*
X167386D01*
Y38906D01*
Y38851D01*
X167332D01*
Y38797D01*
X167278D01*
Y38743D01*
X167224D01*
Y38689D01*
Y38635D01*
X167170D01*
Y38581D01*
X167116D01*
Y38527D01*
X167062D01*
Y38473D01*
X167008D01*
Y38419D01*
X166954D01*
Y38365D01*
X166900D01*
Y38311D01*
X166846D01*
Y38257D01*
X166792D01*
Y38203D01*
X166738D01*
Y38149D01*
X166684D01*
Y38094D01*
X166576D01*
Y38041D01*
X166521D01*
Y37986D01*
X166467D01*
Y37932D01*
X166359D01*
Y37878D01*
X166305D01*
Y37824D01*
X166197D01*
Y37770D01*
X166089D01*
Y37716D01*
X165981D01*
Y37662D01*
X165873D01*
Y37608D01*
X165764D01*
Y37554D01*
X165602D01*
Y37500D01*
X165440D01*
Y37446D01*
X165224D01*
Y37392D01*
X165008D01*
Y37338D01*
X164413D01*
Y37284D01*
X96187D01*
Y37338D01*
X96133D01*
Y37392D01*
Y37446D01*
Y37500D01*
Y37554D01*
Y37608D01*
Y37662D01*
Y37716D01*
Y37770D01*
Y37824D01*
Y37878D01*
Y37932D01*
Y37986D01*
Y38041D01*
Y38094D01*
Y38149D01*
Y38203D01*
Y38257D01*
Y38311D01*
Y38365D01*
Y38419D01*
Y38473D01*
Y38527D01*
Y38581D01*
Y38635D01*
Y38689D01*
Y38743D01*
Y38797D01*
Y38851D01*
Y38906D01*
Y38960D01*
Y39014D01*
Y39068D01*
Y39122D01*
Y39176D01*
Y39230D01*
Y39284D01*
Y39338D01*
Y39392D01*
Y39446D01*
Y39500D01*
Y39554D01*
Y39608D01*
Y39662D01*
Y39716D01*
Y39770D01*
Y39825D01*
Y39879D01*
Y39933D01*
Y39987D01*
Y40041D01*
Y40095D01*
Y40149D01*
Y40203D01*
Y40257D01*
Y40311D01*
Y40365D01*
Y40419D01*
Y40473D01*
Y40527D01*
Y40581D01*
Y40635D01*
Y40690D01*
Y40744D01*
Y40798D01*
Y40852D01*
Y40906D01*
Y40960D01*
Y41014D01*
Y41068D01*
Y41122D01*
Y41176D01*
Y41230D01*
Y41284D01*
Y41338D01*
Y41392D01*
Y41446D01*
Y41500D01*
Y41554D01*
Y41609D01*
Y41663D01*
Y41717D01*
Y41771D01*
Y41825D01*
Y41879D01*
Y41933D01*
Y41987D01*
Y42041D01*
Y42095D01*
Y42149D01*
Y42203D01*
Y42257D01*
Y42311D01*
Y42365D01*
Y42419D01*
Y42474D01*
Y42528D01*
Y42582D01*
Y42636D01*
Y42690D01*
Y42744D01*
Y42798D01*
Y42852D01*
Y42906D01*
Y42960D01*
Y43014D01*
Y43068D01*
Y43122D01*
Y43176D01*
Y43230D01*
Y43284D01*
Y43339D01*
Y43393D01*
Y43447D01*
Y43501D01*
Y43555D01*
Y43609D01*
Y43663D01*
Y43717D01*
Y43771D01*
Y43825D01*
Y43879D01*
Y43933D01*
Y43987D01*
Y44041D01*
Y44095D01*
Y44150D01*
Y44204D01*
Y44258D01*
Y44312D01*
Y44366D01*
Y44420D01*
Y44474D01*
Y44528D01*
Y44582D01*
Y44636D01*
Y44690D01*
Y44744D01*
Y44798D01*
Y44852D01*
Y44906D01*
Y44960D01*
Y45015D01*
Y45068D01*
Y45123D01*
Y45177D01*
Y45231D01*
Y45285D01*
Y45339D01*
Y45393D01*
Y45447D01*
Y45501D01*
Y45555D01*
Y45609D01*
Y45663D01*
Y45717D01*
Y45771D01*
Y45825D01*
Y45880D01*
Y45933D01*
Y45988D01*
Y46042D01*
Y46096D01*
Y46150D01*
Y46204D01*
Y46258D01*
Y46312D01*
Y46366D01*
Y46420D01*
Y46474D01*
Y46528D01*
Y46582D01*
Y46636D01*
Y46690D01*
Y46744D01*
Y46799D01*
Y46853D01*
Y46907D01*
Y46961D01*
Y47015D01*
Y47069D01*
Y47123D01*
Y47177D01*
Y47231D01*
Y47285D01*
Y47339D01*
Y47393D01*
Y47447D01*
Y47501D01*
Y47555D01*
Y47609D01*
Y47664D01*
Y47718D01*
Y47772D01*
Y47826D01*
Y47880D01*
Y47934D01*
Y47988D01*
Y48042D01*
Y48096D01*
Y48150D01*
Y48204D01*
Y48258D01*
Y48312D01*
Y48366D01*
Y48420D01*
Y48474D01*
Y48529D01*
Y48583D01*
Y48637D01*
Y48691D01*
Y48745D01*
Y48799D01*
Y48853D01*
Y48907D01*
Y48961D01*
Y49015D01*
Y49069D01*
Y49123D01*
Y49177D01*
Y49231D01*
Y49285D01*
Y49339D01*
Y49393D01*
Y49448D01*
Y49502D01*
Y49556D01*
Y49610D01*
Y49664D01*
Y49718D01*
Y49772D01*
Y49826D01*
Y49880D01*
Y49934D01*
Y49988D01*
Y50042D01*
Y50096D01*
Y50150D01*
Y50204D01*
Y50258D01*
Y50313D01*
Y50367D01*
Y50421D01*
Y50475D01*
Y50529D01*
Y50583D01*
Y50637D01*
Y50691D01*
Y50745D01*
Y50799D01*
Y50853D01*
Y50907D01*
Y50961D01*
Y51015D01*
Y51069D01*
Y51123D01*
Y51178D01*
Y51232D01*
Y51286D01*
Y51340D01*
Y51394D01*
Y51448D01*
Y51502D01*
Y51556D01*
Y51610D01*
Y51664D01*
Y51718D01*
Y51772D01*
Y51826D01*
Y51880D01*
Y51934D01*
Y51989D01*
Y52043D01*
Y52097D01*
Y52151D01*
Y52205D01*
Y52259D01*
Y52313D01*
Y52367D01*
Y52421D01*
Y52475D01*
Y52529D01*
Y52583D01*
Y52637D01*
Y52691D01*
Y52745D01*
Y52799D01*
Y52854D01*
Y52908D01*
Y52962D01*
Y53016D01*
Y53070D01*
Y53124D01*
Y53178D01*
Y53232D01*
Y53286D01*
Y53340D01*
Y53394D01*
Y53448D01*
Y53502D01*
Y53556D01*
Y53610D01*
Y53664D01*
Y53719D01*
Y53772D01*
Y53827D01*
Y53881D01*
Y53935D01*
Y53989D01*
Y54043D01*
Y54097D01*
Y54151D01*
Y54205D01*
Y54259D01*
Y54313D01*
Y54367D01*
Y54421D01*
Y54475D01*
Y54529D01*
Y54584D01*
Y54637D01*
Y54692D01*
Y54746D01*
Y54800D01*
Y54854D01*
Y54908D01*
Y54962D01*
Y55016D01*
Y55070D01*
Y55124D01*
Y55178D01*
Y55232D01*
Y55286D01*
Y55340D01*
Y55394D01*
Y55449D01*
Y55502D01*
Y55557D01*
Y55611D01*
Y55665D01*
Y55719D01*
Y55773D01*
Y55827D01*
Y55881D01*
Y55935D01*
Y55989D01*
Y56043D01*
Y56097D01*
Y56151D01*
Y56205D01*
Y56259D01*
Y56313D01*
Y56367D01*
Y56422D01*
Y56476D01*
Y56530D01*
Y56584D01*
Y56638D01*
Y56692D01*
Y56746D01*
Y56800D01*
Y56854D01*
Y56908D01*
Y56962D01*
Y57016D01*
Y57070D01*
Y57124D01*
Y57178D01*
Y57232D01*
Y57287D01*
Y57341D01*
Y57395D01*
Y57449D01*
Y57503D01*
Y57557D01*
Y57611D01*
Y57665D01*
Y57719D01*
Y57773D01*
Y57827D01*
Y57881D01*
Y57935D01*
Y57989D01*
Y58043D01*
Y58097D01*
Y58152D01*
Y58206D01*
Y58260D01*
Y58314D01*
Y58368D01*
Y58422D01*
Y58476D01*
Y58530D01*
Y58584D01*
Y58638D01*
Y58692D01*
Y58746D01*
Y58800D01*
Y58854D01*
Y58908D01*
X101377D01*
Y58963D01*
Y59017D01*
Y59071D01*
Y59125D01*
Y59179D01*
Y59233D01*
Y59287D01*
Y59341D01*
Y59395D01*
Y59449D01*
Y59503D01*
Y59557D01*
Y59611D01*
Y59665D01*
Y59719D01*
Y59773D01*
Y59828D01*
Y59882D01*
Y59936D01*
Y59990D01*
Y60044D01*
Y60098D01*
Y60152D01*
Y60206D01*
Y60260D01*
Y60314D01*
Y60368D01*
Y60422D01*
Y60476D01*
Y60530D01*
Y60584D01*
Y60638D01*
Y60693D01*
Y60747D01*
Y60801D01*
Y60855D01*
Y60909D01*
Y60963D01*
Y61017D01*
Y61071D01*
Y61125D01*
Y61179D01*
Y61233D01*
Y61287D01*
Y61341D01*
Y61395D01*
Y61449D01*
Y61503D01*
Y61557D01*
Y61611D01*
Y61666D01*
Y61720D01*
Y61774D01*
Y61828D01*
Y61882D01*
Y61936D01*
Y61990D01*
Y62044D01*
Y62098D01*
Y62152D01*
Y62206D01*
Y62260D01*
Y62314D01*
Y62368D01*
Y62423D01*
Y62476D01*
Y62531D01*
Y62585D01*
Y62639D01*
Y62693D01*
Y62747D01*
Y62801D01*
Y62855D01*
Y62909D01*
Y62963D01*
Y63017D01*
Y63071D01*
Y63125D01*
Y63179D01*
Y63233D01*
Y63287D01*
Y63341D01*
Y63396D01*
Y63450D01*
Y63504D01*
Y63558D01*
Y63612D01*
Y63666D01*
Y63720D01*
Y63774D01*
Y63828D01*
Y63882D01*
Y63936D01*
Y63990D01*
Y64044D01*
Y64098D01*
Y64152D01*
Y64206D01*
Y64261D01*
Y64315D01*
Y64369D01*
Y64423D01*
Y64477D01*
Y64531D01*
Y64585D01*
Y64639D01*
Y64693D01*
Y64747D01*
Y64801D01*
Y64855D01*
X96187D01*
Y64909D01*
X96133D01*
Y64963D01*
Y65017D01*
Y65071D01*
Y65126D01*
Y65180D01*
Y65234D01*
Y65288D01*
Y65342D01*
Y65396D01*
Y65450D01*
Y65504D01*
Y65558D01*
Y65612D01*
Y65666D01*
Y65720D01*
Y65774D01*
Y65828D01*
Y65882D01*
Y65936D01*
Y65991D01*
Y66045D01*
Y66099D01*
Y66153D01*
Y66207D01*
X101377D01*
Y66261D01*
Y66315D01*
Y66369D01*
Y66423D01*
Y66477D01*
Y66531D01*
Y66585D01*
Y66639D01*
Y66693D01*
Y66747D01*
Y66802D01*
Y66856D01*
Y66910D01*
Y66964D01*
Y67018D01*
Y67072D01*
Y67126D01*
Y67180D01*
Y67234D01*
Y67288D01*
Y67342D01*
Y67396D01*
Y67450D01*
Y67504D01*
Y67558D01*
Y67612D01*
Y67667D01*
Y67721D01*
Y67775D01*
Y67829D01*
Y67883D01*
Y67937D01*
Y67991D01*
Y68045D01*
Y68099D01*
Y68153D01*
Y68207D01*
Y68261D01*
Y68315D01*
Y68369D01*
Y68423D01*
Y68477D01*
Y68531D01*
Y68585D01*
Y68640D01*
Y68694D01*
Y68748D01*
Y68802D01*
Y68856D01*
Y68910D01*
Y68964D01*
Y69018D01*
Y69072D01*
Y69126D01*
Y69180D01*
Y69234D01*
Y69288D01*
Y69342D01*
Y69397D01*
Y69450D01*
Y69505D01*
Y69559D01*
Y69613D01*
Y69667D01*
Y69721D01*
Y69775D01*
Y69829D01*
Y69883D01*
Y69937D01*
Y69991D01*
Y70045D01*
Y70099D01*
Y70153D01*
Y70207D01*
Y70261D01*
Y70315D01*
Y70370D01*
Y70424D01*
Y70478D01*
Y70532D01*
Y70586D01*
Y70640D01*
Y70694D01*
Y70748D01*
Y70802D01*
Y70856D01*
Y70910D01*
Y70964D01*
Y71018D01*
Y71072D01*
Y71126D01*
Y71180D01*
Y71235D01*
Y71289D01*
Y71343D01*
Y71397D01*
Y71451D01*
Y71505D01*
Y71559D01*
Y71613D01*
Y71667D01*
Y71721D01*
Y71775D01*
Y71829D01*
Y71883D01*
Y71937D01*
Y71991D01*
Y72045D01*
Y72100D01*
Y72154D01*
Y72208D01*
X96133D01*
Y72262D01*
Y72316D01*
Y72370D01*
Y72424D01*
Y72478D01*
Y72532D01*
Y72586D01*
Y72640D01*
Y72694D01*
Y72748D01*
Y72802D01*
Y72856D01*
Y72910D01*
Y72965D01*
Y73019D01*
Y73073D01*
Y73127D01*
Y73181D01*
Y73235D01*
Y73289D01*
Y73343D01*
Y73397D01*
Y73451D01*
Y73505D01*
X96187D01*
Y73559D01*
X101377D01*
Y73613D01*
Y73667D01*
Y73721D01*
Y73776D01*
Y73830D01*
Y73884D01*
Y73938D01*
Y73992D01*
Y74046D01*
Y74100D01*
Y74154D01*
Y74208D01*
Y74262D01*
Y74316D01*
Y74370D01*
Y74424D01*
Y74478D01*
Y74532D01*
Y74586D01*
Y74641D01*
Y74695D01*
Y74749D01*
Y74803D01*
Y74857D01*
Y74911D01*
Y74965D01*
Y75019D01*
Y75073D01*
Y75127D01*
Y75181D01*
Y75235D01*
Y75289D01*
Y75343D01*
Y75397D01*
Y75451D01*
Y75505D01*
Y75560D01*
Y75614D01*
Y75668D01*
Y75722D01*
Y75776D01*
Y75830D01*
Y75884D01*
Y75938D01*
Y75992D01*
Y76046D01*
Y76100D01*
Y76154D01*
Y76208D01*
Y76262D01*
Y76316D01*
Y76371D01*
Y76424D01*
Y76479D01*
Y76533D01*
Y76587D01*
Y76641D01*
Y76695D01*
Y76749D01*
Y76803D01*
Y76857D01*
Y76911D01*
Y76965D01*
Y77019D01*
Y77073D01*
Y77127D01*
Y77181D01*
Y77235D01*
Y77289D01*
Y77344D01*
Y77398D01*
Y77452D01*
Y77506D01*
Y77560D01*
Y77614D01*
Y77668D01*
Y77722D01*
Y77776D01*
Y77830D01*
Y77884D01*
Y77938D01*
Y77992D01*
Y78046D01*
Y78100D01*
Y78154D01*
Y78209D01*
Y78263D01*
Y78317D01*
Y78371D01*
Y78425D01*
Y78479D01*
Y78533D01*
Y78587D01*
Y78641D01*
Y78695D01*
Y78749D01*
Y78803D01*
Y78857D01*
Y78911D01*
Y78965D01*
Y79019D01*
Y79074D01*
Y79128D01*
Y79182D01*
Y79236D01*
Y79290D01*
Y79344D01*
Y79398D01*
Y79452D01*
Y79506D01*
X96133D01*
Y79560D01*
Y79614D01*
Y79668D01*
Y79722D01*
Y79776D01*
Y79830D01*
Y79884D01*
Y79939D01*
Y79993D01*
Y80047D01*
Y80101D01*
Y80155D01*
Y80209D01*
Y80263D01*
Y80317D01*
Y80371D01*
Y80425D01*
Y80479D01*
Y80533D01*
Y80587D01*
Y80641D01*
Y80695D01*
Y80749D01*
Y80804D01*
Y80858D01*
X101377D01*
Y80912D01*
Y80966D01*
Y81020D01*
Y81074D01*
Y81128D01*
Y81182D01*
Y81236D01*
Y81290D01*
Y81344D01*
Y81398D01*
Y81452D01*
Y81506D01*
Y81560D01*
Y81615D01*
Y81669D01*
Y81723D01*
Y81777D01*
Y81831D01*
Y81885D01*
Y81939D01*
Y81993D01*
Y82047D01*
Y82101D01*
Y82155D01*
Y82209D01*
Y82263D01*
Y82317D01*
Y82371D01*
Y82425D01*
Y82479D01*
Y82534D01*
Y82588D01*
Y82642D01*
Y82696D01*
Y82750D01*
Y82804D01*
Y82858D01*
Y82912D01*
Y82966D01*
Y83020D01*
Y83074D01*
Y83128D01*
Y83182D01*
Y83236D01*
Y83290D01*
Y83344D01*
Y83398D01*
Y83453D01*
Y83507D01*
Y83561D01*
Y83615D01*
Y83669D01*
Y83723D01*
Y83777D01*
Y83831D01*
Y83885D01*
Y83939D01*
Y83993D01*
Y84047D01*
Y84101D01*
Y84155D01*
Y84209D01*
Y84263D01*
Y84318D01*
Y84372D01*
Y84426D01*
Y84480D01*
Y84534D01*
Y84588D01*
Y84642D01*
Y84696D01*
Y84750D01*
Y84804D01*
Y84858D01*
Y84912D01*
Y84966D01*
Y85020D01*
Y85074D01*
Y85128D01*
Y85183D01*
Y85237D01*
Y85291D01*
Y85345D01*
Y85399D01*
Y85453D01*
Y85507D01*
Y85561D01*
Y85615D01*
Y85669D01*
Y85723D01*
Y85777D01*
Y85831D01*
Y85885D01*
Y85939D01*
Y85993D01*
Y86048D01*
Y86102D01*
Y86156D01*
Y86210D01*
Y86264D01*
Y86318D01*
Y86372D01*
Y86426D01*
Y86480D01*
Y86534D01*
Y86588D01*
Y86642D01*
Y86696D01*
Y86750D01*
Y86804D01*
X96133D01*
Y86858D01*
Y86913D01*
Y86967D01*
Y87021D01*
Y87075D01*
Y87129D01*
Y87183D01*
Y87237D01*
Y87291D01*
Y87345D01*
Y87399D01*
Y87453D01*
Y87507D01*
Y87561D01*
Y87615D01*
Y87669D01*
Y87723D01*
Y87778D01*
Y87832D01*
Y87886D01*
Y87940D01*
Y87994D01*
Y88048D01*
Y88102D01*
Y88156D01*
Y88210D01*
Y88264D01*
Y88318D01*
Y88372D01*
Y88426D01*
Y88480D01*
Y88534D01*
Y88589D01*
Y88643D01*
Y88697D01*
Y88751D01*
Y88805D01*
Y88859D01*
Y88913D01*
Y88967D01*
Y89021D01*
Y89075D01*
Y89129D01*
Y89183D01*
Y89237D01*
Y89291D01*
Y89345D01*
Y89399D01*
Y89453D01*
Y89508D01*
Y89562D01*
Y89616D01*
Y89670D01*
Y89724D01*
Y89778D01*
Y89832D01*
Y89886D01*
Y89940D01*
Y89994D01*
Y90048D01*
Y90102D01*
Y90156D01*
Y90210D01*
Y90264D01*
Y90318D01*
Y90373D01*
Y90427D01*
Y90481D01*
Y90535D01*
Y90589D01*
Y90643D01*
Y90697D01*
Y90751D01*
Y90805D01*
Y90859D01*
Y90913D01*
Y90967D01*
Y91021D01*
Y91075D01*
Y91129D01*
Y91183D01*
Y91237D01*
Y91292D01*
Y91346D01*
Y91400D01*
Y91454D01*
Y91508D01*
Y91562D01*
Y91616D01*
Y91670D01*
X104188D01*
Y91616D01*
Y91562D01*
Y91508D01*
Y91454D01*
Y91400D01*
Y91346D01*
Y91292D01*
Y91237D01*
Y91183D01*
Y91129D01*
Y91075D01*
Y91021D01*
Y90967D01*
Y90913D01*
Y90859D01*
Y90805D01*
Y90751D01*
Y90697D01*
Y90643D01*
Y90589D01*
Y90535D01*
Y90481D01*
Y90427D01*
Y90373D01*
Y90318D01*
Y90264D01*
Y90210D01*
Y90156D01*
Y90102D01*
Y90048D01*
Y89994D01*
Y89940D01*
Y89886D01*
Y89832D01*
Y89778D01*
Y89724D01*
Y89670D01*
Y89616D01*
Y89562D01*
Y89508D01*
Y89453D01*
Y89399D01*
Y89345D01*
Y89291D01*
Y89237D01*
Y89183D01*
Y89129D01*
Y89075D01*
Y89021D01*
Y88967D01*
Y88913D01*
Y88859D01*
Y88805D01*
Y88751D01*
Y88697D01*
Y88643D01*
Y88589D01*
Y88534D01*
Y88480D01*
Y88426D01*
Y88372D01*
Y88318D01*
Y88264D01*
Y88210D01*
Y88156D01*
Y88102D01*
Y88048D01*
Y87994D01*
Y87940D01*
Y87886D01*
Y87832D01*
Y87778D01*
Y87723D01*
Y87669D01*
Y87615D01*
Y87561D01*
Y87507D01*
Y87453D01*
Y87399D01*
Y87345D01*
Y87291D01*
Y87237D01*
Y87183D01*
Y87129D01*
Y87075D01*
Y87021D01*
Y86967D01*
X104242D01*
Y86913D01*
Y86858D01*
X104296D01*
Y86804D01*
X104350D01*
Y86750D01*
X104404D01*
Y86696D01*
X104512D01*
Y86642D01*
X112892D01*
Y86696D01*
X113000D01*
Y86750D01*
X113108D01*
Y86804D01*
X113162D01*
Y86858D01*
Y86913D01*
X113216D01*
Y86967D01*
Y87021D01*
Y87075D01*
Y87129D01*
Y87183D01*
Y87237D01*
X113270D01*
Y87291D01*
X113216D01*
Y87345D01*
X113270D01*
Y87399D01*
Y87453D01*
X113216D01*
Y87507D01*
Y87561D01*
Y87615D01*
Y87669D01*
Y87723D01*
Y87778D01*
Y87832D01*
Y87886D01*
Y87940D01*
Y87994D01*
Y88048D01*
Y88102D01*
Y88156D01*
Y88210D01*
Y88264D01*
Y88318D01*
Y88372D01*
Y88426D01*
Y88480D01*
Y88534D01*
Y88589D01*
Y88643D01*
Y88697D01*
Y88751D01*
Y88805D01*
Y88859D01*
Y88913D01*
Y88967D01*
Y89021D01*
Y89075D01*
Y89129D01*
Y89183D01*
Y89237D01*
Y89291D01*
Y89345D01*
Y89399D01*
Y89453D01*
Y89508D01*
Y89562D01*
Y89616D01*
Y89670D01*
Y89724D01*
Y89778D01*
Y89832D01*
Y89886D01*
Y89940D01*
Y89994D01*
Y90048D01*
Y90102D01*
Y90156D01*
Y90210D01*
X113270D01*
Y90264D01*
Y90318D01*
Y90373D01*
X113324D01*
Y90427D01*
X113378D01*
Y90481D01*
X113433D01*
Y90535D01*
X113487D01*
Y90589D01*
X113649D01*
Y90643D01*
X116893D01*
Y90589D01*
X117055D01*
Y90535D01*
X117109D01*
Y90481D01*
X117163D01*
Y90427D01*
X117217D01*
Y90373D01*
X117271D01*
Y90318D01*
Y90264D01*
Y90210D01*
Y90156D01*
X117325D01*
Y90102D01*
Y90048D01*
Y89994D01*
Y89940D01*
Y89886D01*
Y89832D01*
Y89778D01*
Y89724D01*
Y89670D01*
Y89616D01*
Y89562D01*
Y89508D01*
Y89453D01*
Y89399D01*
Y89345D01*
Y89291D01*
Y89237D01*
Y89183D01*
Y89129D01*
Y89075D01*
Y89021D01*
Y88967D01*
Y88913D01*
Y88859D01*
Y88805D01*
Y88751D01*
Y88697D01*
Y88643D01*
Y88589D01*
Y88534D01*
Y88480D01*
Y88426D01*
Y88372D01*
Y88318D01*
Y88264D01*
Y88210D01*
Y88156D01*
Y88102D01*
Y88048D01*
Y87994D01*
Y87940D01*
Y87886D01*
Y87832D01*
X117271D01*
Y87778D01*
X117325D01*
Y87723D01*
Y87669D01*
X117271D01*
Y87615D01*
X117325D01*
Y87561D01*
Y87507D01*
Y87453D01*
Y87399D01*
Y87345D01*
Y87291D01*
X117379D01*
Y87237D01*
Y87183D01*
X117433D01*
Y87129D01*
Y87075D01*
X117487D01*
Y87021D01*
X117541D01*
Y86967D01*
X117595D01*
Y86913D01*
X117649D01*
Y86858D01*
X117703D01*
Y86804D01*
X117812D01*
Y86750D01*
X117920D01*
Y86696D01*
X118082D01*
Y86642D01*
X118514D01*
Y86696D01*
X118676D01*
Y86750D01*
X118785D01*
Y86804D01*
X118893D01*
Y86858D01*
X118947D01*
Y86913D01*
X119001D01*
Y86967D01*
X119055D01*
Y87021D01*
X119109D01*
Y87075D01*
Y87129D01*
X119163D01*
Y87183D01*
Y87237D01*
X119217D01*
Y87291D01*
Y87345D01*
X119271D01*
Y87399D01*
Y87453D01*
Y87507D01*
Y87561D01*
Y87615D01*
Y87669D01*
Y87723D01*
Y87778D01*
Y87832D01*
X119325D01*
Y87886D01*
X119271D01*
Y87940D01*
Y87994D01*
Y88048D01*
Y88102D01*
Y88156D01*
Y88210D01*
Y88264D01*
Y88318D01*
Y88372D01*
Y88426D01*
Y88480D01*
Y88534D01*
Y88589D01*
Y88643D01*
Y88697D01*
Y88751D01*
Y88805D01*
Y88859D01*
Y88913D01*
Y88967D01*
Y89021D01*
Y89075D01*
Y89129D01*
Y89183D01*
Y89237D01*
Y89291D01*
Y89345D01*
Y89399D01*
Y89453D01*
Y89508D01*
Y89562D01*
Y89616D01*
Y89670D01*
Y89724D01*
Y89778D01*
Y89832D01*
Y89886D01*
Y89940D01*
Y89994D01*
Y90048D01*
Y90102D01*
Y90156D01*
Y90210D01*
Y90264D01*
Y90318D01*
Y90373D01*
Y90427D01*
Y90481D01*
Y90535D01*
Y90589D01*
Y90643D01*
Y90697D01*
Y90751D01*
Y90805D01*
Y90859D01*
Y90913D01*
Y90967D01*
Y91021D01*
Y91075D01*
Y91129D01*
Y91183D01*
Y91237D01*
Y91292D01*
Y91346D01*
Y91400D01*
Y91454D01*
Y91508D01*
Y91562D01*
Y91616D01*
Y91670D01*
Y91724D01*
Y91778D01*
Y91832D01*
Y91886D01*
Y91940D01*
Y91994D01*
Y92048D01*
Y92102D01*
Y92157D01*
Y92211D01*
Y92265D01*
X119325D01*
Y92319D01*
Y92373D01*
Y92427D01*
X119379D01*
Y92481D01*
Y92535D01*
X119433D01*
Y92589D01*
X119542D01*
Y92643D01*
X119650D01*
Y92697D01*
X124948D01*
Y92643D01*
X125110D01*
Y92589D01*
X125164D01*
Y92535D01*
X125218D01*
Y92481D01*
X125272D01*
Y92427D01*
X125326D01*
Y92373D01*
Y92319D01*
Y92265D01*
Y92211D01*
Y92157D01*
Y92102D01*
Y92048D01*
Y91994D01*
Y91940D01*
Y91886D01*
Y91832D01*
Y91778D01*
Y91724D01*
Y91670D01*
Y91616D01*
Y91562D01*
Y91508D01*
Y91454D01*
Y91400D01*
Y91346D01*
Y91292D01*
Y91237D01*
Y91183D01*
Y91129D01*
Y91075D01*
Y91021D01*
Y90967D01*
Y90913D01*
Y90859D01*
Y90805D01*
Y90751D01*
Y90697D01*
Y90643D01*
Y90589D01*
Y90535D01*
Y90481D01*
Y90427D01*
Y90373D01*
Y90318D01*
Y90264D01*
Y90210D01*
Y90156D01*
Y90102D01*
Y90048D01*
Y89994D01*
Y89940D01*
Y89886D01*
Y89832D01*
Y89778D01*
Y89724D01*
Y89670D01*
Y89616D01*
Y89562D01*
Y89508D01*
Y89453D01*
Y89399D01*
Y89345D01*
Y89291D01*
Y89237D01*
Y89183D01*
Y89129D01*
X125380D01*
Y89075D01*
Y89021D01*
Y88967D01*
Y88913D01*
X125434D01*
Y88859D01*
X125488D01*
Y88805D01*
X125542D01*
Y88751D01*
X125596D01*
Y88697D01*
X125759D01*
Y88643D01*
X125921D01*
Y88697D01*
X126083D01*
Y88751D01*
X126191D01*
Y88805D01*
X126245D01*
Y88859D01*
Y88913D01*
X126299D01*
Y88967D01*
Y89021D01*
Y89075D01*
X126353D01*
Y89129D01*
Y89183D01*
Y89237D01*
Y89291D01*
Y89345D01*
Y89399D01*
Y89453D01*
Y89508D01*
Y89562D01*
Y89616D01*
Y89670D01*
Y89724D01*
Y89778D01*
Y89832D01*
Y89886D01*
Y89940D01*
Y89994D01*
Y90048D01*
Y90102D01*
Y90156D01*
Y90210D01*
Y90264D01*
Y90318D01*
Y90373D01*
Y90427D01*
Y90481D01*
Y90535D01*
Y90589D01*
Y90643D01*
Y90697D01*
Y90751D01*
Y90805D01*
Y90859D01*
Y90913D01*
Y90967D01*
Y91021D01*
Y91075D01*
Y91129D01*
Y91183D01*
Y91237D01*
Y91292D01*
Y91346D01*
Y91400D01*
Y91454D01*
Y91508D01*
Y91562D01*
Y91616D01*
Y91670D01*
Y91724D01*
Y91778D01*
Y91832D01*
Y91886D01*
Y91940D01*
Y91994D01*
Y92048D01*
Y92102D01*
Y92157D01*
Y92211D01*
Y92265D01*
Y92319D01*
Y92373D01*
X126407D01*
Y92427D01*
Y92481D01*
X126462D01*
Y92535D01*
X126515D01*
Y92589D01*
X126570D01*
Y92643D01*
X126732D01*
Y92697D01*
X137058D01*
Y92643D01*
D02*
G37*
G36*
X29075Y88378D02*
X29063D01*
Y88389D01*
X29075D01*
Y88378D01*
D02*
G37*
G36*
X28983Y88113D02*
X28960D01*
Y88125D01*
X28983D01*
Y88113D01*
D02*
G37*
G36*
X29213Y88044D02*
X29225D01*
Y88021D01*
X29202D01*
Y88055D01*
X29213D01*
Y88044D01*
D02*
G37*
G36*
X28465Y86858D02*
D01*
D01*
D01*
D01*
D02*
G37*
G36*
X30710Y86696D02*
X30687D01*
Y86708D01*
X30710D01*
Y86696D01*
D02*
G37*
G36*
X28004Y86386D02*
X27981D01*
Y86397D01*
X28004D01*
Y86386D01*
D02*
G37*
G36*
X27969Y86374D02*
X27946D01*
Y86386D01*
X27969D01*
Y86374D01*
D02*
G37*
G36*
X27900D02*
X27877D01*
Y86386D01*
X27900D01*
Y86374D01*
D02*
G37*
G36*
X29605Y85902D02*
X29593D01*
Y85925D01*
Y85936D01*
X29605D01*
Y85902D01*
D02*
G37*
G36*
Y85867D02*
Y85856D01*
X29593D01*
Y85879D01*
X29605D01*
Y85867D01*
D02*
G37*
G36*
X98836Y85777D02*
X98998D01*
Y85723D01*
X99160D01*
Y85669D01*
X99268D01*
Y85615D01*
X99376D01*
Y85561D01*
X99484D01*
Y85507D01*
X99539D01*
Y85453D01*
X99647D01*
Y85399D01*
X99701D01*
Y85345D01*
X99755D01*
Y85291D01*
X99809D01*
Y85237D01*
X99863D01*
Y85183D01*
X99917D01*
Y85128D01*
X99971D01*
Y85074D01*
X100025D01*
Y85020D01*
Y84966D01*
X100079D01*
Y84912D01*
X100133D01*
Y84858D01*
Y84804D01*
X100187D01*
Y84750D01*
Y84696D01*
X100241D01*
Y84642D01*
Y84588D01*
X100295D01*
Y84534D01*
Y84480D01*
Y84426D01*
X100349D01*
Y84372D01*
Y84318D01*
Y84263D01*
Y84209D01*
Y84155D01*
X100404D01*
Y84101D01*
Y84047D01*
Y83993D01*
Y83939D01*
Y83885D01*
Y83831D01*
Y83777D01*
Y83723D01*
Y83669D01*
Y83615D01*
Y83561D01*
Y83507D01*
X100349D01*
Y83453D01*
Y83398D01*
Y83344D01*
Y83290D01*
Y83236D01*
X100295D01*
Y83182D01*
Y83128D01*
Y83074D01*
X100241D01*
Y83020D01*
Y82966D01*
X100187D01*
Y82912D01*
Y82858D01*
X100133D01*
Y82804D01*
Y82750D01*
X100079D01*
Y82696D01*
X100025D01*
Y82642D01*
Y82588D01*
X99971D01*
Y82534D01*
X99917D01*
Y82479D01*
X99863D01*
Y82425D01*
X99809D01*
Y82371D01*
X99755D01*
Y82317D01*
X99701D01*
Y82263D01*
X99647D01*
Y82209D01*
X99539D01*
Y82155D01*
X99484D01*
Y82101D01*
X99376D01*
Y82047D01*
X99268D01*
Y81993D01*
X99160D01*
Y81939D01*
X99052D01*
Y81885D01*
X98836D01*
Y81831D01*
X97917D01*
Y81885D01*
X97755D01*
Y81939D01*
X97592D01*
Y81993D01*
X97484D01*
Y82047D01*
X97376D01*
Y82101D01*
X97268D01*
Y82155D01*
X97214D01*
Y82209D01*
X97106D01*
Y82263D01*
X97052D01*
Y82317D01*
X96998D01*
Y82371D01*
X96944D01*
Y82425D01*
X96890D01*
Y82479D01*
X96836D01*
Y82534D01*
X96781D01*
Y82588D01*
Y82642D01*
X96727D01*
Y82696D01*
X96673D01*
Y82750D01*
Y82804D01*
X96619D01*
Y82858D01*
Y82912D01*
X96565D01*
Y82966D01*
Y83020D01*
X96511D01*
Y83074D01*
Y83128D01*
X96457D01*
Y83182D01*
Y83236D01*
Y83290D01*
X96403D01*
Y83344D01*
Y83398D01*
Y83453D01*
Y83507D01*
Y83561D01*
X96349D01*
Y83615D01*
Y83669D01*
Y83723D01*
Y83777D01*
Y83831D01*
Y83885D01*
Y83939D01*
Y83993D01*
Y84047D01*
Y84101D01*
X96403D01*
Y84155D01*
Y84209D01*
Y84263D01*
Y84318D01*
Y84372D01*
X96457D01*
Y84426D01*
Y84480D01*
Y84534D01*
X96511D01*
Y84588D01*
Y84642D01*
X96565D01*
Y84696D01*
Y84750D01*
X96619D01*
Y84804D01*
Y84858D01*
X96673D01*
Y84912D01*
Y84966D01*
X96727D01*
Y85020D01*
X96781D01*
Y85074D01*
Y85128D01*
X96836D01*
Y85183D01*
X96890D01*
Y85237D01*
X96944D01*
Y85291D01*
X96998D01*
Y85345D01*
X97052D01*
Y85399D01*
X97160D01*
Y85453D01*
X97214D01*
Y85507D01*
X97268D01*
Y85561D01*
X97376D01*
Y85615D01*
X97484D01*
Y85669D01*
X97592D01*
Y85723D01*
X97755D01*
Y85777D01*
X97917D01*
Y85831D01*
X98836D01*
Y85777D01*
D02*
G37*
G36*
X98782Y78479D02*
X98998D01*
Y78425D01*
X99106D01*
Y78371D01*
X99268D01*
Y78317D01*
X99376D01*
Y78263D01*
X99430D01*
Y78209D01*
X99539D01*
Y78154D01*
X99593D01*
Y78100D01*
X99701D01*
Y78046D01*
X99755D01*
Y77992D01*
X99809D01*
Y77938D01*
X99863D01*
Y77884D01*
X99917D01*
Y77830D01*
X99971D01*
Y77776D01*
Y77722D01*
X100025D01*
Y77668D01*
X100079D01*
Y77614D01*
Y77560D01*
X100133D01*
Y77506D01*
X100187D01*
Y77452D01*
Y77398D01*
X100241D01*
Y77344D01*
Y77289D01*
Y77235D01*
X100295D01*
Y77181D01*
Y77127D01*
Y77073D01*
X100349D01*
Y77019D01*
Y76965D01*
Y76911D01*
Y76857D01*
X100404D01*
Y76803D01*
Y76749D01*
Y76695D01*
Y76641D01*
Y76587D01*
Y76533D01*
Y76479D01*
Y76424D01*
Y76371D01*
Y76316D01*
Y76262D01*
Y76208D01*
Y76154D01*
X100349D01*
Y76100D01*
Y76046D01*
Y75992D01*
Y75938D01*
X100295D01*
Y75884D01*
Y75830D01*
Y75776D01*
X100241D01*
Y75722D01*
Y75668D01*
X100187D01*
Y75614D01*
Y75560D01*
X100133D01*
Y75505D01*
Y75451D01*
X100079D01*
Y75397D01*
X100025D01*
Y75343D01*
Y75289D01*
X99971D01*
Y75235D01*
X99917D01*
Y75181D01*
X99863D01*
Y75127D01*
X99809D01*
Y75073D01*
X99755D01*
Y75019D01*
X99701D01*
Y74965D01*
X99647D01*
Y74911D01*
X99593D01*
Y74857D01*
X99484D01*
Y74803D01*
X99430D01*
Y74749D01*
X99322D01*
Y74695D01*
X99214D01*
Y74641D01*
X99052D01*
Y74586D01*
X98890D01*
Y74532D01*
X98620D01*
Y74478D01*
X98133D01*
Y74532D01*
X97863D01*
Y74586D01*
X97701D01*
Y74641D01*
X97538D01*
Y74695D01*
X97430D01*
Y74749D01*
X97376D01*
Y74803D01*
X97268D01*
Y74857D01*
X97160D01*
Y74911D01*
X97106D01*
Y74965D01*
X97052D01*
Y75019D01*
X96998D01*
Y75073D01*
X96944D01*
Y75127D01*
X96890D01*
Y75181D01*
X96836D01*
Y75235D01*
X96781D01*
Y75289D01*
X96727D01*
Y75343D01*
Y75397D01*
X96673D01*
Y75451D01*
X96619D01*
Y75505D01*
Y75560D01*
X96565D01*
Y75614D01*
Y75668D01*
X96511D01*
Y75722D01*
Y75776D01*
Y75830D01*
X96457D01*
Y75884D01*
Y75938D01*
Y75992D01*
X96403D01*
Y76046D01*
Y76100D01*
Y76154D01*
Y76208D01*
Y76262D01*
X96349D01*
Y76316D01*
Y76371D01*
Y76424D01*
Y76479D01*
Y76533D01*
Y76587D01*
Y76641D01*
Y76695D01*
Y76749D01*
Y76803D01*
X96403D01*
Y76857D01*
Y76911D01*
Y76965D01*
Y77019D01*
Y77073D01*
X96457D01*
Y77127D01*
Y77181D01*
Y77235D01*
X96511D01*
Y77289D01*
Y77344D01*
X96565D01*
Y77398D01*
Y77452D01*
X96619D01*
Y77506D01*
Y77560D01*
X96673D01*
Y77614D01*
Y77668D01*
X96727D01*
Y77722D01*
X96781D01*
Y77776D01*
X96836D01*
Y77830D01*
Y77884D01*
X96890D01*
Y77938D01*
X96944D01*
Y77992D01*
X96998D01*
Y78046D01*
X97106D01*
Y78100D01*
X97160D01*
Y78154D01*
X97214D01*
Y78209D01*
X97322D01*
Y78263D01*
X97430D01*
Y78317D01*
X97484D01*
Y78371D01*
X97646D01*
Y78425D01*
X97809D01*
Y78479D01*
X97971D01*
Y78533D01*
X98782D01*
Y78479D01*
D02*
G37*
G36*
X192958Y72532D02*
X193282D01*
Y72478D01*
X193552D01*
Y72424D01*
X193769D01*
Y72370D01*
X193931D01*
Y72316D01*
X194039D01*
Y72262D01*
X194201D01*
Y72208D01*
X194309D01*
Y72154D01*
X194417D01*
Y72100D01*
X194472D01*
Y72045D01*
X194580D01*
Y71991D01*
X194688D01*
Y71937D01*
X194742D01*
Y71883D01*
X194796D01*
Y71829D01*
X194904D01*
Y71775D01*
X194958D01*
Y71721D01*
X195012D01*
Y71667D01*
X195066D01*
Y71613D01*
X195120D01*
Y71559D01*
X195174D01*
Y71505D01*
X195228D01*
Y71451D01*
X195282D01*
Y71397D01*
X195336D01*
Y71343D01*
X195390D01*
Y71289D01*
X195445D01*
Y71235D01*
X195499D01*
Y71180D01*
X195553D01*
Y71126D01*
Y71072D01*
X195607D01*
Y71018D01*
X195661D01*
Y70964D01*
Y70910D01*
X195715D01*
Y70856D01*
X195769D01*
Y70802D01*
Y70748D01*
X195823D01*
Y70694D01*
Y70640D01*
X195877D01*
Y70586D01*
Y70532D01*
X195931D01*
Y70478D01*
Y70424D01*
X195985D01*
Y70370D01*
Y70315D01*
X196039D01*
Y70261D01*
Y70207D01*
Y70153D01*
X196093D01*
Y70099D01*
Y70045D01*
Y69991D01*
X196147D01*
Y69937D01*
Y69883D01*
Y69829D01*
Y69775D01*
X196201D01*
Y69721D01*
Y69667D01*
Y69613D01*
Y69559D01*
Y69505D01*
Y69450D01*
X196256D01*
Y69397D01*
Y69342D01*
Y69288D01*
Y69234D01*
Y69180D01*
Y69126D01*
Y69072D01*
Y69018D01*
Y68964D01*
Y68910D01*
Y68856D01*
Y68802D01*
Y68748D01*
Y68694D01*
Y68640D01*
X196201D01*
Y68585D01*
Y68531D01*
Y68477D01*
Y68423D01*
Y68369D01*
Y68315D01*
X196147D01*
Y68261D01*
Y68207D01*
Y68153D01*
Y68099D01*
X196093D01*
Y68045D01*
Y67991D01*
Y67937D01*
X196039D01*
Y67883D01*
Y67829D01*
Y67775D01*
X195985D01*
Y67721D01*
Y67667D01*
X195931D01*
Y67612D01*
Y67558D01*
Y67504D01*
X195877D01*
Y67450D01*
Y67396D01*
X195823D01*
Y67342D01*
X195769D01*
Y67288D01*
Y67234D01*
X195715D01*
Y67180D01*
Y67126D01*
X195661D01*
Y67072D01*
X195607D01*
Y67018D01*
Y66964D01*
X195553D01*
Y66910D01*
X195499D01*
Y66856D01*
X195445D01*
Y66802D01*
Y66747D01*
X195390D01*
Y66693D01*
X195336D01*
Y66639D01*
X195282D01*
Y66585D01*
X195228D01*
Y66531D01*
X195174D01*
Y66477D01*
X195120D01*
Y66423D01*
X195066D01*
Y66369D01*
X194958D01*
Y66315D01*
X194904D01*
Y66261D01*
X194850D01*
Y66207D01*
X194796D01*
Y66153D01*
X194688D01*
Y66099D01*
X194634D01*
Y66045D01*
X194526D01*
Y65991D01*
X194417D01*
Y65936D01*
X194363D01*
Y65882D01*
X194255D01*
Y65828D01*
X194093D01*
Y65774D01*
X193985D01*
Y65720D01*
X193823D01*
Y65666D01*
X193660D01*
Y65612D01*
X193444D01*
Y65558D01*
X193120D01*
Y65504D01*
X192147D01*
Y65558D01*
X191876D01*
Y65612D01*
X191660D01*
Y65666D01*
X191498D01*
Y65720D01*
X191336D01*
Y65774D01*
X191174D01*
Y65828D01*
X191066D01*
Y65882D01*
X190957D01*
Y65936D01*
X190849D01*
Y65991D01*
X190795D01*
Y66045D01*
X190687D01*
Y66099D01*
X190633D01*
Y66153D01*
X190525D01*
Y66207D01*
X190471D01*
Y66261D01*
X190363D01*
Y66315D01*
X190309D01*
Y66369D01*
X190255D01*
Y66423D01*
X190201D01*
Y66477D01*
X190147D01*
Y66531D01*
X190093D01*
Y66585D01*
X190038D01*
Y66639D01*
X189984D01*
Y66693D01*
X189930D01*
Y66747D01*
X189876D01*
Y66802D01*
X189822D01*
Y66856D01*
Y66910D01*
X189768D01*
Y66964D01*
X189714D01*
Y67018D01*
X189660D01*
Y67072D01*
Y67126D01*
X189606D01*
Y67180D01*
X189552D01*
Y67234D01*
Y67288D01*
X189498D01*
Y67342D01*
Y67396D01*
X189444D01*
Y67450D01*
Y67504D01*
X189390D01*
Y67558D01*
Y67612D01*
X189336D01*
Y67667D01*
Y67721D01*
X189281D01*
Y67775D01*
Y67829D01*
Y67883D01*
X189227D01*
Y67937D01*
Y67991D01*
Y68045D01*
X189173D01*
Y68099D01*
Y68153D01*
Y68207D01*
Y68261D01*
X189119D01*
Y68315D01*
Y68369D01*
Y68423D01*
Y68477D01*
Y68531D01*
X189065D01*
Y68585D01*
Y68640D01*
Y68694D01*
Y68748D01*
Y68802D01*
Y68856D01*
Y68910D01*
Y68964D01*
Y69018D01*
Y69072D01*
Y69126D01*
Y69180D01*
Y69234D01*
Y69288D01*
Y69342D01*
Y69397D01*
Y69450D01*
Y69505D01*
Y69559D01*
X189119D01*
Y69613D01*
Y69667D01*
Y69721D01*
Y69775D01*
Y69829D01*
X189173D01*
Y69883D01*
Y69937D01*
Y69991D01*
Y70045D01*
X189227D01*
Y70099D01*
Y70153D01*
Y70207D01*
X189281D01*
Y70261D01*
Y70315D01*
X189336D01*
Y70370D01*
Y70424D01*
Y70478D01*
X189390D01*
Y70532D01*
Y70586D01*
X189444D01*
Y70640D01*
Y70694D01*
X189498D01*
Y70748D01*
X189552D01*
Y70802D01*
Y70856D01*
X189606D01*
Y70910D01*
Y70964D01*
X189660D01*
Y71018D01*
X189714D01*
Y71072D01*
Y71126D01*
X189768D01*
Y71180D01*
X189822D01*
Y71235D01*
X189876D01*
Y71289D01*
X189930D01*
Y71343D01*
Y71397D01*
X189984D01*
Y71451D01*
X190038D01*
Y71505D01*
X190093D01*
Y71559D01*
X190147D01*
Y71613D01*
X190201D01*
Y71667D01*
X190309D01*
Y71721D01*
X190363D01*
Y71775D01*
X190417D01*
Y71829D01*
X190471D01*
Y71883D01*
X190579D01*
Y71937D01*
X190633D01*
Y71991D01*
X190741D01*
Y72045D01*
X190795D01*
Y72100D01*
X190903D01*
Y72154D01*
X191012D01*
Y72208D01*
X191120D01*
Y72262D01*
X191228D01*
Y72316D01*
X191390D01*
Y72370D01*
X191552D01*
Y72424D01*
X191714D01*
Y72478D01*
X191985D01*
Y72532D01*
X192363D01*
Y72586D01*
X192742D01*
Y72532D01*
X192796D01*
Y72586D01*
X192850D01*
Y72532D01*
X192904D01*
Y72586D01*
X192958D01*
Y72532D01*
D02*
G37*
G36*
X98674Y71180D02*
X98944D01*
Y71126D01*
X99106D01*
Y71072D01*
X99214D01*
Y71018D01*
X99322D01*
Y70964D01*
X99430D01*
Y70910D01*
X99539D01*
Y70856D01*
X99593D01*
Y70802D01*
X99647D01*
Y70748D01*
X99701D01*
Y70694D01*
X99809D01*
Y70640D01*
X99863D01*
Y70586D01*
X99917D01*
Y70532D01*
Y70478D01*
X99971D01*
Y70424D01*
X100025D01*
Y70370D01*
X100079D01*
Y70315D01*
Y70261D01*
X100133D01*
Y70207D01*
Y70153D01*
X100187D01*
Y70099D01*
Y70045D01*
X100241D01*
Y69991D01*
Y69937D01*
X100295D01*
Y69883D01*
Y69829D01*
Y69775D01*
X100349D01*
Y69721D01*
Y69667D01*
Y69613D01*
Y69559D01*
X100404D01*
Y69505D01*
Y69450D01*
Y69397D01*
Y69342D01*
Y69288D01*
Y69234D01*
Y69180D01*
Y69126D01*
Y69072D01*
Y69018D01*
Y68964D01*
Y68910D01*
Y68856D01*
X100349D01*
Y68802D01*
Y68748D01*
Y68694D01*
Y68640D01*
X100295D01*
Y68585D01*
Y68531D01*
Y68477D01*
X100241D01*
Y68423D01*
Y68369D01*
X100187D01*
Y68315D01*
Y68261D01*
X100133D01*
Y68207D01*
Y68153D01*
X100079D01*
Y68099D01*
Y68045D01*
X100025D01*
Y67991D01*
X99971D01*
Y67937D01*
X99917D01*
Y67883D01*
Y67829D01*
X99863D01*
Y67775D01*
X99809D01*
Y67721D01*
X99755D01*
Y67667D01*
X99647D01*
Y67612D01*
X99593D01*
Y67558D01*
X99539D01*
Y67504D01*
X99430D01*
Y67450D01*
X99322D01*
Y67396D01*
X99214D01*
Y67342D01*
X99106D01*
Y67288D01*
X98944D01*
Y67234D01*
X98728D01*
Y67180D01*
X98079D01*
Y67234D01*
X97809D01*
Y67288D01*
X97646D01*
Y67342D01*
X97538D01*
Y67396D01*
X97430D01*
Y67450D01*
X97322D01*
Y67504D01*
X97268D01*
Y67558D01*
X97160D01*
Y67612D01*
X97106D01*
Y67667D01*
X97052D01*
Y67721D01*
X96998D01*
Y67775D01*
X96944D01*
Y67829D01*
X96890D01*
Y67883D01*
X96836D01*
Y67937D01*
X96781D01*
Y67991D01*
X96727D01*
Y68045D01*
Y68099D01*
X96673D01*
Y68153D01*
X96619D01*
Y68207D01*
Y68261D01*
X96565D01*
Y68315D01*
Y68369D01*
X96511D01*
Y68423D01*
Y68477D01*
X96457D01*
Y68531D01*
Y68585D01*
Y68640D01*
Y68694D01*
X96403D01*
Y68748D01*
Y68802D01*
Y68856D01*
Y68910D01*
X96349D01*
Y68964D01*
Y69018D01*
Y69072D01*
Y69126D01*
Y69180D01*
Y69234D01*
Y69288D01*
Y69342D01*
Y69397D01*
Y69450D01*
Y69505D01*
X96403D01*
Y69559D01*
Y69613D01*
Y69667D01*
Y69721D01*
X96457D01*
Y69775D01*
Y69829D01*
Y69883D01*
X96511D01*
Y69937D01*
Y69991D01*
Y70045D01*
X96565D01*
Y70099D01*
Y70153D01*
X96619D01*
Y70207D01*
Y70261D01*
X96673D01*
Y70315D01*
X96727D01*
Y70370D01*
Y70424D01*
X96781D01*
Y70478D01*
X96836D01*
Y70532D01*
X96890D01*
Y70586D01*
X96944D01*
Y70640D01*
X96998D01*
Y70694D01*
X97052D01*
Y70748D01*
X97106D01*
Y70802D01*
X97160D01*
Y70856D01*
X97268D01*
Y70910D01*
X97322D01*
Y70964D01*
X97430D01*
Y71018D01*
X97538D01*
Y71072D01*
X97646D01*
Y71126D01*
X97809D01*
Y71180D01*
X98079D01*
Y71235D01*
X98674D01*
Y71180D01*
D02*
G37*
G36*
X98566Y63882D02*
X98890D01*
Y63828D01*
X99052D01*
Y63774D01*
X99214D01*
Y63720D01*
X99322D01*
Y63666D01*
X99430D01*
Y63612D01*
X99484D01*
Y63558D01*
X99593D01*
Y63504D01*
X99647D01*
Y63450D01*
X99701D01*
Y63396D01*
X99755D01*
Y63341D01*
X99809D01*
Y63287D01*
X99863D01*
Y63233D01*
X99917D01*
Y63179D01*
X99971D01*
Y63125D01*
X100025D01*
Y63071D01*
Y63017D01*
X100079D01*
Y62963D01*
X100133D01*
Y62909D01*
Y62855D01*
X100187D01*
Y62801D01*
Y62747D01*
X100241D01*
Y62693D01*
Y62639D01*
X100295D01*
Y62585D01*
Y62531D01*
Y62476D01*
X100349D01*
Y62423D01*
Y62368D01*
Y62314D01*
Y62260D01*
X100404D01*
Y62206D01*
Y62152D01*
Y62098D01*
Y62044D01*
Y61990D01*
Y61936D01*
Y61882D01*
Y61828D01*
Y61774D01*
Y61720D01*
Y61666D01*
Y61611D01*
Y61557D01*
X100349D01*
Y61503D01*
Y61449D01*
Y61395D01*
Y61341D01*
X100295D01*
Y61287D01*
Y61233D01*
Y61179D01*
X100241D01*
Y61125D01*
Y61071D01*
Y61017D01*
X100187D01*
Y60963D01*
Y60909D01*
X100133D01*
Y60855D01*
X100079D01*
Y60801D01*
Y60747D01*
X100025D01*
Y60693D01*
X99971D01*
Y60638D01*
Y60584D01*
X99917D01*
Y60530D01*
X99863D01*
Y60476D01*
X99809D01*
Y60422D01*
X99755D01*
Y60368D01*
X99701D01*
Y60314D01*
X99593D01*
Y60260D01*
X99539D01*
Y60206D01*
X99430D01*
Y60152D01*
X99376D01*
Y60098D01*
X99268D01*
Y60044D01*
X99160D01*
Y59990D01*
X98998D01*
Y59936D01*
X98782D01*
Y59882D01*
X97971D01*
Y59936D01*
X97755D01*
Y59990D01*
X97646D01*
Y60044D01*
X97484D01*
Y60098D01*
X97376D01*
Y60152D01*
X97322D01*
Y60206D01*
X97214D01*
Y60260D01*
X97160D01*
Y60314D01*
X97106D01*
Y60368D01*
X96998D01*
Y60422D01*
X96944D01*
Y60476D01*
X96890D01*
Y60530D01*
X96836D01*
Y60584D01*
Y60638D01*
X96781D01*
Y60693D01*
X96727D01*
Y60747D01*
X96673D01*
Y60801D01*
Y60855D01*
X96619D01*
Y60909D01*
Y60963D01*
X96565D01*
Y61017D01*
Y61071D01*
X96511D01*
Y61125D01*
Y61179D01*
X96457D01*
Y61233D01*
Y61287D01*
Y61341D01*
X96403D01*
Y61395D01*
Y61449D01*
Y61503D01*
Y61557D01*
Y61611D01*
X96349D01*
Y61666D01*
Y61720D01*
Y61774D01*
Y61828D01*
Y61882D01*
Y61936D01*
Y61990D01*
Y62044D01*
Y62098D01*
Y62152D01*
X96403D01*
Y62206D01*
Y62260D01*
Y62314D01*
Y62368D01*
Y62423D01*
X96457D01*
Y62476D01*
Y62531D01*
Y62585D01*
X96511D01*
Y62639D01*
Y62693D01*
Y62747D01*
X96565D01*
Y62801D01*
Y62855D01*
X96619D01*
Y62909D01*
X96673D01*
Y62963D01*
Y63017D01*
X96727D01*
Y63071D01*
Y63125D01*
X96781D01*
Y63179D01*
X96836D01*
Y63233D01*
X96890D01*
Y63287D01*
X96944D01*
Y63341D01*
X96998D01*
Y63396D01*
X97052D01*
Y63450D01*
X97106D01*
Y63504D01*
X97214D01*
Y63558D01*
X97268D01*
Y63612D01*
X97376D01*
Y63666D01*
X97430D01*
Y63720D01*
X97592D01*
Y63774D01*
X97701D01*
Y63828D01*
X97863D01*
Y63882D01*
X98187D01*
Y63936D01*
X98566D01*
Y63882D01*
D02*
G37*
G36*
X181172Y44312D02*
X181442D01*
Y44258D01*
X181659D01*
Y44204D01*
X181821D01*
Y44150D01*
X181983D01*
Y44095D01*
X182091D01*
Y44041D01*
X182199D01*
Y43987D01*
X182308D01*
Y43933D01*
X182416D01*
Y43879D01*
X182524D01*
Y43825D01*
X182578D01*
Y43771D01*
X182686D01*
Y43717D01*
X182740D01*
Y43663D01*
X182794D01*
Y43609D01*
X182848D01*
Y43555D01*
X182956D01*
Y43501D01*
X183010D01*
Y43447D01*
X183064D01*
Y43393D01*
X183118D01*
Y43339D01*
X183173D01*
Y43284D01*
X183227D01*
Y43230D01*
X183281D01*
Y43176D01*
X183335D01*
Y43122D01*
X183389D01*
Y43068D01*
Y43014D01*
X183443D01*
Y42960D01*
X183497D01*
Y42906D01*
X183551D01*
Y42852D01*
Y42798D01*
X183605D01*
Y42744D01*
X183659D01*
Y42690D01*
Y42636D01*
X183713D01*
Y42582D01*
Y42528D01*
X183767D01*
Y42474D01*
Y42419D01*
X183821D01*
Y42365D01*
Y42311D01*
X183875D01*
Y42257D01*
Y42203D01*
X183929D01*
Y42149D01*
Y42095D01*
Y42041D01*
X183983D01*
Y41987D01*
Y41933D01*
Y41879D01*
X184037D01*
Y41825D01*
Y41771D01*
Y41717D01*
X184092D01*
Y41663D01*
Y41609D01*
Y41554D01*
Y41500D01*
Y41446D01*
X184146D01*
Y41392D01*
Y41338D01*
Y41284D01*
Y41230D01*
Y41176D01*
Y41122D01*
Y41068D01*
Y41014D01*
Y40960D01*
X184200D01*
Y40906D01*
Y40852D01*
Y40798D01*
Y40744D01*
X184146D01*
Y40690D01*
Y40635D01*
Y40581D01*
Y40527D01*
Y40473D01*
Y40419D01*
Y40365D01*
Y40311D01*
Y40257D01*
Y40203D01*
X184092D01*
Y40149D01*
Y40095D01*
Y40041D01*
Y39987D01*
X184037D01*
Y39933D01*
Y39879D01*
Y39825D01*
Y39770D01*
X183983D01*
Y39716D01*
Y39662D01*
Y39608D01*
X183929D01*
Y39554D01*
Y39500D01*
X183875D01*
Y39446D01*
Y39392D01*
Y39338D01*
X183821D01*
Y39284D01*
Y39230D01*
X183767D01*
Y39176D01*
X183713D01*
Y39122D01*
Y39068D01*
X183659D01*
Y39014D01*
Y38960D01*
X183605D01*
Y38906D01*
X183551D01*
Y38851D01*
Y38797D01*
X183497D01*
Y38743D01*
X183443D01*
Y38689D01*
Y38635D01*
X183389D01*
Y38581D01*
X183335D01*
Y38527D01*
X183281D01*
Y38473D01*
X183227D01*
Y38419D01*
X183173D01*
Y38365D01*
X183118D01*
Y38311D01*
X183064D01*
Y38257D01*
X183010D01*
Y38203D01*
X182956D01*
Y38149D01*
X182902D01*
Y38094D01*
X182848D01*
Y38041D01*
X182740D01*
Y37986D01*
X182686D01*
Y37932D01*
X182578D01*
Y37878D01*
X182524D01*
Y37824D01*
X182416D01*
Y37770D01*
X182308D01*
Y37716D01*
X182253D01*
Y37662D01*
X182091D01*
Y37608D01*
X181983D01*
Y37554D01*
X181821D01*
Y37500D01*
X181713D01*
Y37446D01*
X181497D01*
Y37392D01*
X181226D01*
Y37338D01*
X180686D01*
Y37284D01*
X180632D01*
Y37338D01*
X180578D01*
Y37284D01*
X176469D01*
Y37338D01*
X175874D01*
Y37392D01*
X175658D01*
Y37446D01*
X175442D01*
Y37500D01*
X175279D01*
Y37554D01*
X175171D01*
Y37608D01*
X175009D01*
Y37662D01*
X174901D01*
Y37716D01*
X174793D01*
Y37770D01*
X174685D01*
Y37824D01*
X174631D01*
Y37878D01*
X174523D01*
Y37932D01*
X174469D01*
Y37986D01*
X174360D01*
Y38041D01*
X174306D01*
Y38094D01*
X174252D01*
Y38149D01*
X174198D01*
Y38203D01*
X174144D01*
Y38257D01*
X174090D01*
Y38311D01*
X174036D01*
Y38365D01*
X173982D01*
Y38419D01*
X173928D01*
Y38473D01*
X173874D01*
Y38527D01*
X173820D01*
Y38581D01*
X173766D01*
Y38635D01*
X173712D01*
Y38689D01*
X173658D01*
Y38743D01*
Y38797D01*
X173603D01*
Y38851D01*
X173549D01*
Y38906D01*
Y38960D01*
X173495D01*
Y39014D01*
X173441D01*
Y39068D01*
Y39122D01*
X173387D01*
Y39176D01*
Y39230D01*
X173333D01*
Y39284D01*
Y39338D01*
X173279D01*
Y39392D01*
Y39446D01*
X173225D01*
Y39500D01*
Y39554D01*
Y39608D01*
X173171D01*
Y39662D01*
Y39716D01*
X173117D01*
Y39770D01*
Y39825D01*
Y39879D01*
Y39933D01*
X173063D01*
Y39987D01*
Y40041D01*
Y40095D01*
Y40149D01*
X173009D01*
Y40203D01*
Y40257D01*
Y40311D01*
Y40365D01*
Y40419D01*
Y40473D01*
Y40527D01*
X172955D01*
Y40581D01*
Y40635D01*
Y40690D01*
Y40744D01*
Y40798D01*
Y40852D01*
Y40906D01*
Y40960D01*
Y41014D01*
Y41068D01*
Y41122D01*
Y41176D01*
Y41230D01*
X173009D01*
Y41284D01*
Y41338D01*
Y41392D01*
Y41446D01*
Y41500D01*
X173063D01*
Y41554D01*
Y41609D01*
Y41663D01*
Y41717D01*
Y41771D01*
X173117D01*
Y41825D01*
Y41879D01*
Y41933D01*
X173171D01*
Y41987D01*
Y42041D01*
Y42095D01*
X173225D01*
Y42149D01*
Y42203D01*
Y42257D01*
X173279D01*
Y42311D01*
Y42365D01*
X173333D01*
Y42419D01*
Y42474D01*
X173387D01*
Y42528D01*
Y42582D01*
X173441D01*
Y42636D01*
X173495D01*
Y42690D01*
Y42744D01*
X173549D01*
Y42798D01*
Y42852D01*
X173603D01*
Y42906D01*
X173658D01*
Y42960D01*
X173712D01*
Y43014D01*
Y43068D01*
X173766D01*
Y43122D01*
X173820D01*
Y43176D01*
X173874D01*
Y43230D01*
X173928D01*
Y43284D01*
X173982D01*
Y43339D01*
X174036D01*
Y43393D01*
X174090D01*
Y43447D01*
X174144D01*
Y43501D01*
X174198D01*
Y43555D01*
X174252D01*
Y43609D01*
X174306D01*
Y43663D01*
X174415D01*
Y43717D01*
X174469D01*
Y43771D01*
X174577D01*
Y43825D01*
X174631D01*
Y43879D01*
X174739D01*
Y43933D01*
X174847D01*
Y43987D01*
X174901D01*
Y44041D01*
X175063D01*
Y44095D01*
X175171D01*
Y44150D01*
X175333D01*
Y44204D01*
X175496D01*
Y44258D01*
X175658D01*
Y44312D01*
X175928D01*
Y44366D01*
X181172D01*
Y44312D01*
D02*
G37*
G36*
X94132Y99022D02*
Y98968D01*
Y98914D01*
Y98860D01*
Y98806D01*
Y98752D01*
Y98698D01*
Y98644D01*
Y98590D01*
Y98536D01*
Y98482D01*
Y98428D01*
Y98374D01*
Y98320D01*
Y98266D01*
Y98211D01*
Y98157D01*
Y98103D01*
Y98049D01*
Y97995D01*
Y97941D01*
Y97887D01*
Y97833D01*
Y97779D01*
Y97725D01*
Y97671D01*
Y97617D01*
Y97563D01*
Y97509D01*
Y97455D01*
Y97401D01*
Y97347D01*
Y97292D01*
Y97238D01*
Y97184D01*
Y97130D01*
Y97076D01*
Y97022D01*
Y96968D01*
Y96914D01*
Y96860D01*
Y96806D01*
Y96752D01*
Y96698D01*
Y96644D01*
Y96590D01*
Y96536D01*
Y96482D01*
Y96427D01*
Y96373D01*
Y96319D01*
Y96265D01*
Y96211D01*
Y96157D01*
Y96103D01*
Y96049D01*
Y95995D01*
Y95941D01*
Y95887D01*
Y95833D01*
Y95779D01*
Y95725D01*
Y95671D01*
Y95617D01*
Y95562D01*
Y95508D01*
Y95454D01*
Y95400D01*
Y95346D01*
Y95292D01*
Y95238D01*
Y95184D01*
Y95130D01*
Y95076D01*
Y95022D01*
Y94968D01*
Y94914D01*
Y94860D01*
Y94806D01*
Y94752D01*
Y94697D01*
Y94643D01*
Y94589D01*
Y94535D01*
Y94481D01*
Y94427D01*
Y94373D01*
Y94319D01*
Y94265D01*
Y94211D01*
Y94157D01*
Y94103D01*
Y94049D01*
Y93995D01*
Y93941D01*
Y93887D01*
Y93832D01*
Y93778D01*
Y93724D01*
Y93670D01*
Y93616D01*
Y93562D01*
Y93508D01*
Y93454D01*
Y93400D01*
Y93346D01*
Y93292D01*
Y93238D01*
Y93184D01*
Y93130D01*
Y93076D01*
Y93022D01*
Y92967D01*
Y92913D01*
Y92859D01*
Y92805D01*
Y92751D01*
Y92697D01*
Y92643D01*
Y92589D01*
Y92535D01*
Y92481D01*
Y92427D01*
Y92373D01*
Y92319D01*
Y92265D01*
Y92211D01*
Y92157D01*
Y92102D01*
Y92048D01*
Y91994D01*
Y91940D01*
Y91886D01*
Y91832D01*
Y91778D01*
Y91724D01*
Y91670D01*
Y91616D01*
Y91562D01*
Y91508D01*
Y91454D01*
Y91400D01*
Y91346D01*
Y91292D01*
Y91237D01*
Y91183D01*
Y91129D01*
Y91075D01*
Y91021D01*
Y90967D01*
Y90913D01*
Y90859D01*
Y90805D01*
Y90751D01*
Y90697D01*
Y90643D01*
Y90589D01*
Y90535D01*
Y90481D01*
Y90427D01*
Y90373D01*
Y90318D01*
Y90264D01*
Y90210D01*
Y90156D01*
Y90102D01*
Y90048D01*
Y89994D01*
Y89940D01*
Y89886D01*
Y89832D01*
Y89778D01*
Y89724D01*
Y89670D01*
Y89616D01*
Y89562D01*
Y89508D01*
Y89453D01*
Y89399D01*
Y89345D01*
Y89291D01*
Y89237D01*
Y89183D01*
Y89129D01*
Y89075D01*
Y89021D01*
Y88967D01*
Y88913D01*
Y88859D01*
Y88805D01*
Y88751D01*
Y88697D01*
Y88643D01*
Y88589D01*
Y88534D01*
Y88480D01*
Y88426D01*
Y88372D01*
Y88318D01*
Y88264D01*
Y88210D01*
Y88156D01*
Y88102D01*
Y88048D01*
Y87994D01*
Y87940D01*
Y87886D01*
Y87832D01*
Y87778D01*
Y87723D01*
Y87669D01*
Y87615D01*
Y87561D01*
Y87507D01*
Y87453D01*
Y87399D01*
Y87345D01*
Y87291D01*
Y87237D01*
Y87183D01*
Y87129D01*
Y87075D01*
Y87021D01*
Y86967D01*
Y86913D01*
Y86858D01*
Y86804D01*
Y86750D01*
Y86696D01*
Y86642D01*
Y86588D01*
Y86534D01*
Y86480D01*
Y86426D01*
Y86372D01*
Y86318D01*
Y86264D01*
Y86210D01*
Y86156D01*
Y86102D01*
Y86048D01*
Y85993D01*
Y85939D01*
Y85885D01*
Y85831D01*
Y85777D01*
Y85723D01*
Y85669D01*
Y85615D01*
Y85561D01*
Y85507D01*
Y85453D01*
Y85399D01*
Y85345D01*
Y85291D01*
Y85237D01*
Y85183D01*
Y85128D01*
Y85074D01*
Y85020D01*
Y84966D01*
Y84912D01*
Y84858D01*
Y84804D01*
Y84750D01*
Y84696D01*
Y84642D01*
Y84588D01*
Y84534D01*
Y84480D01*
Y84426D01*
Y84372D01*
Y84318D01*
Y84263D01*
Y84209D01*
Y84155D01*
Y84101D01*
Y84047D01*
Y83993D01*
Y83939D01*
Y83885D01*
Y83831D01*
Y83777D01*
Y83723D01*
Y83669D01*
Y83615D01*
Y83561D01*
Y83507D01*
Y83453D01*
Y83398D01*
Y83344D01*
Y83290D01*
Y83236D01*
Y83182D01*
Y83128D01*
Y83074D01*
Y83020D01*
Y82966D01*
Y82912D01*
Y82858D01*
Y82804D01*
Y82750D01*
Y82696D01*
Y82642D01*
Y82588D01*
Y82534D01*
Y82479D01*
Y82425D01*
Y82371D01*
Y82317D01*
Y82263D01*
Y82209D01*
Y82155D01*
Y82101D01*
Y82047D01*
Y81993D01*
Y81939D01*
Y81885D01*
Y81831D01*
Y81777D01*
Y81723D01*
Y81669D01*
Y81615D01*
Y81560D01*
Y81506D01*
Y81452D01*
Y81398D01*
Y81344D01*
Y81290D01*
Y81236D01*
Y81182D01*
Y81128D01*
Y81074D01*
Y81020D01*
Y80966D01*
Y80912D01*
Y80858D01*
Y80804D01*
Y80749D01*
Y80695D01*
Y80641D01*
Y80587D01*
Y80533D01*
Y80479D01*
Y80425D01*
Y80371D01*
Y80317D01*
Y80263D01*
Y80209D01*
Y80155D01*
Y80101D01*
Y80047D01*
Y79993D01*
Y79939D01*
Y79884D01*
Y79830D01*
Y79776D01*
Y79722D01*
Y79668D01*
Y79614D01*
Y79560D01*
Y79506D01*
Y79452D01*
Y79398D01*
Y79344D01*
Y79290D01*
Y79236D01*
Y79182D01*
Y79128D01*
Y79074D01*
Y79019D01*
Y78965D01*
Y78911D01*
Y78857D01*
Y78803D01*
Y78749D01*
Y78695D01*
Y78641D01*
Y78587D01*
Y78533D01*
Y78479D01*
Y78425D01*
Y78371D01*
Y78317D01*
Y78263D01*
Y78209D01*
Y78154D01*
Y78100D01*
Y78046D01*
Y77992D01*
Y77938D01*
Y77884D01*
Y77830D01*
Y77776D01*
Y77722D01*
Y77668D01*
Y77614D01*
Y77560D01*
Y77506D01*
Y77452D01*
Y77398D01*
Y77344D01*
Y77289D01*
Y77235D01*
Y77181D01*
Y77127D01*
Y77073D01*
Y77019D01*
Y76965D01*
Y76911D01*
Y76857D01*
Y76803D01*
Y76749D01*
Y76695D01*
Y76641D01*
Y76587D01*
Y76533D01*
Y76479D01*
Y76424D01*
Y76371D01*
Y76316D01*
Y76262D01*
Y76208D01*
Y76154D01*
Y76100D01*
Y76046D01*
Y75992D01*
Y75938D01*
Y75884D01*
Y75830D01*
Y75776D01*
Y75722D01*
Y75668D01*
Y75614D01*
Y75560D01*
Y75505D01*
Y75451D01*
Y75397D01*
Y75343D01*
Y75289D01*
Y75235D01*
Y75181D01*
Y75127D01*
Y75073D01*
Y75019D01*
Y74965D01*
Y74911D01*
Y74857D01*
Y74803D01*
Y74749D01*
Y74695D01*
Y74641D01*
Y74586D01*
Y74532D01*
Y74478D01*
Y74424D01*
Y74370D01*
Y74316D01*
Y74262D01*
Y74208D01*
Y74154D01*
Y74100D01*
Y74046D01*
Y73992D01*
Y73938D01*
Y73884D01*
Y73830D01*
Y73776D01*
Y73721D01*
Y73667D01*
Y73613D01*
Y73559D01*
Y73505D01*
Y73451D01*
Y73397D01*
Y73343D01*
Y73289D01*
Y73235D01*
Y73181D01*
Y73127D01*
Y73073D01*
Y73019D01*
Y72965D01*
Y72910D01*
Y72856D01*
Y72802D01*
Y72748D01*
Y72694D01*
Y72640D01*
Y72586D01*
Y72532D01*
Y72478D01*
Y72424D01*
Y72370D01*
Y72316D01*
Y72262D01*
Y72208D01*
Y72154D01*
Y72100D01*
Y72045D01*
Y71991D01*
Y71937D01*
Y71883D01*
Y71829D01*
Y71775D01*
Y71721D01*
Y71667D01*
Y71613D01*
Y71559D01*
Y71505D01*
Y71451D01*
Y71397D01*
Y71343D01*
Y71289D01*
Y71235D01*
Y71180D01*
Y71126D01*
Y71072D01*
Y71018D01*
Y70964D01*
Y70910D01*
Y70856D01*
Y70802D01*
Y70748D01*
Y70694D01*
Y70640D01*
Y70586D01*
Y70532D01*
Y70478D01*
Y70424D01*
Y70370D01*
Y70315D01*
Y70261D01*
Y70207D01*
Y70153D01*
Y70099D01*
Y70045D01*
Y69991D01*
Y69937D01*
Y69883D01*
Y69829D01*
Y69775D01*
Y69721D01*
Y69667D01*
Y69613D01*
Y69559D01*
Y69505D01*
Y69450D01*
Y69397D01*
Y69342D01*
Y69288D01*
Y69234D01*
Y69180D01*
Y69126D01*
Y69072D01*
Y69018D01*
Y68964D01*
Y68910D01*
Y68856D01*
Y68802D01*
Y68748D01*
Y68694D01*
Y68640D01*
Y68585D01*
Y68531D01*
Y68477D01*
Y68423D01*
Y68369D01*
Y68315D01*
Y68261D01*
Y68207D01*
Y68153D01*
Y68099D01*
Y68045D01*
Y67991D01*
Y67937D01*
Y67883D01*
Y67829D01*
Y67775D01*
Y67721D01*
Y67667D01*
Y67612D01*
Y67558D01*
Y67504D01*
Y67450D01*
Y67396D01*
Y67342D01*
Y67288D01*
Y67234D01*
Y67180D01*
Y67126D01*
Y67072D01*
Y67018D01*
Y66964D01*
Y66910D01*
Y66856D01*
Y66802D01*
Y66747D01*
Y66693D01*
Y66639D01*
Y66585D01*
Y66531D01*
Y66477D01*
Y66423D01*
Y66369D01*
Y66315D01*
Y66261D01*
Y66207D01*
Y66153D01*
Y66099D01*
Y66045D01*
Y65991D01*
Y65936D01*
Y65882D01*
Y65828D01*
Y65774D01*
Y65720D01*
Y65666D01*
Y65612D01*
Y65558D01*
Y65504D01*
Y65450D01*
Y65396D01*
Y65342D01*
Y65288D01*
Y65234D01*
Y65180D01*
Y65126D01*
Y65071D01*
Y65017D01*
Y64963D01*
Y64909D01*
Y64855D01*
Y64801D01*
Y64747D01*
Y64693D01*
Y64639D01*
Y64585D01*
Y64531D01*
Y64477D01*
Y64423D01*
Y64369D01*
Y64315D01*
Y64261D01*
Y64206D01*
Y64152D01*
Y64098D01*
Y64044D01*
Y63990D01*
Y63936D01*
Y63882D01*
Y63828D01*
Y63774D01*
Y63720D01*
Y63666D01*
Y63612D01*
Y63558D01*
Y63504D01*
Y63450D01*
Y63396D01*
Y63341D01*
Y63287D01*
Y63233D01*
Y63179D01*
Y63125D01*
Y63071D01*
Y63017D01*
Y62963D01*
Y62909D01*
Y62855D01*
Y62801D01*
Y62747D01*
Y62693D01*
Y62639D01*
Y62585D01*
Y62531D01*
Y62476D01*
Y62423D01*
Y62368D01*
Y62314D01*
Y62260D01*
Y62206D01*
Y62152D01*
Y62098D01*
Y62044D01*
Y61990D01*
Y61936D01*
Y61882D01*
Y61828D01*
Y61774D01*
Y61720D01*
Y61666D01*
Y61611D01*
Y61557D01*
Y61503D01*
Y61449D01*
Y61395D01*
Y61341D01*
Y61287D01*
Y61233D01*
Y61179D01*
Y61125D01*
Y61071D01*
Y61017D01*
Y60963D01*
Y60909D01*
Y60855D01*
Y60801D01*
Y60747D01*
Y60693D01*
Y60638D01*
Y60584D01*
Y60530D01*
Y60476D01*
Y60422D01*
Y60368D01*
Y60314D01*
Y60260D01*
Y60206D01*
Y60152D01*
Y60098D01*
Y60044D01*
Y59990D01*
Y59936D01*
Y59882D01*
Y59828D01*
Y59773D01*
Y59719D01*
Y59665D01*
Y59611D01*
Y59557D01*
Y59503D01*
Y59449D01*
Y59395D01*
Y59341D01*
Y59287D01*
Y59233D01*
Y59179D01*
Y59125D01*
Y59071D01*
Y59017D01*
Y58963D01*
Y58908D01*
Y58854D01*
Y58800D01*
Y58746D01*
Y58692D01*
Y58638D01*
Y58584D01*
Y58530D01*
Y58476D01*
Y58422D01*
Y58368D01*
Y58314D01*
Y58260D01*
Y58206D01*
Y58152D01*
Y58097D01*
Y58043D01*
Y57989D01*
Y57935D01*
Y57881D01*
Y57827D01*
Y57773D01*
Y57719D01*
Y57665D01*
Y57611D01*
Y57557D01*
Y57503D01*
Y57449D01*
Y57395D01*
Y57341D01*
Y57287D01*
Y57232D01*
Y57178D01*
Y57124D01*
Y57070D01*
Y57016D01*
Y56962D01*
Y56908D01*
Y56854D01*
Y56800D01*
Y56746D01*
Y56692D01*
Y56638D01*
Y56584D01*
Y56530D01*
Y56476D01*
Y56422D01*
Y56367D01*
Y56313D01*
Y56259D01*
Y56205D01*
Y56151D01*
Y56097D01*
Y56043D01*
Y55989D01*
Y55935D01*
Y55881D01*
Y55827D01*
Y55773D01*
Y55719D01*
Y55665D01*
Y55611D01*
Y55557D01*
Y55502D01*
Y55449D01*
Y55394D01*
Y55340D01*
Y55286D01*
Y55232D01*
Y55178D01*
Y55124D01*
Y55070D01*
Y55016D01*
Y54962D01*
Y54908D01*
Y54854D01*
Y54800D01*
Y54746D01*
Y54692D01*
Y54637D01*
Y54584D01*
Y54529D01*
Y54475D01*
Y54421D01*
Y54367D01*
Y54313D01*
Y54259D01*
Y54205D01*
Y54151D01*
Y54097D01*
Y54043D01*
Y53989D01*
Y53935D01*
Y53881D01*
Y53827D01*
Y53772D01*
Y53719D01*
Y53664D01*
Y53610D01*
Y53556D01*
Y53502D01*
Y53448D01*
Y53394D01*
Y53340D01*
Y53286D01*
Y53232D01*
Y53178D01*
Y53124D01*
Y53070D01*
Y53016D01*
Y52962D01*
Y52908D01*
Y52854D01*
Y52799D01*
Y52745D01*
Y52691D01*
Y52637D01*
Y52583D01*
Y52529D01*
Y52475D01*
Y52421D01*
Y52367D01*
Y52313D01*
Y52259D01*
Y52205D01*
Y52151D01*
Y52097D01*
Y52043D01*
Y51989D01*
Y51934D01*
Y51880D01*
Y51826D01*
Y51772D01*
Y51718D01*
Y51664D01*
Y51610D01*
Y51556D01*
Y51502D01*
Y51448D01*
Y51394D01*
Y51340D01*
Y51286D01*
Y51232D01*
Y51178D01*
Y51123D01*
Y51069D01*
Y51015D01*
Y50961D01*
Y50907D01*
Y50853D01*
Y50799D01*
Y50745D01*
Y50691D01*
Y50637D01*
Y50583D01*
Y50529D01*
Y50475D01*
Y50421D01*
Y50367D01*
Y50313D01*
Y50258D01*
Y50204D01*
Y50150D01*
Y50096D01*
Y50042D01*
Y49988D01*
Y49934D01*
Y49880D01*
Y49826D01*
Y49772D01*
Y49718D01*
Y49664D01*
Y49610D01*
Y49556D01*
Y49502D01*
Y49448D01*
Y49393D01*
Y49339D01*
Y49285D01*
Y49231D01*
Y49177D01*
Y49123D01*
Y49069D01*
Y49015D01*
Y48961D01*
Y48907D01*
Y48853D01*
Y48799D01*
Y48745D01*
Y48691D01*
Y48637D01*
Y48583D01*
Y48529D01*
Y48474D01*
Y48420D01*
Y48366D01*
Y48312D01*
Y48258D01*
Y48204D01*
Y48150D01*
Y48096D01*
Y48042D01*
Y47988D01*
Y47934D01*
Y47880D01*
Y47826D01*
Y47772D01*
Y47718D01*
Y47664D01*
Y47609D01*
Y47555D01*
Y47501D01*
Y47447D01*
Y47393D01*
Y47339D01*
Y47285D01*
Y47231D01*
Y47177D01*
Y47123D01*
Y47069D01*
Y47015D01*
Y46961D01*
Y46907D01*
Y46853D01*
Y46799D01*
Y46744D01*
Y46690D01*
Y46636D01*
Y46582D01*
Y46528D01*
Y46474D01*
Y46420D01*
Y46366D01*
Y46312D01*
Y46258D01*
Y46204D01*
Y46150D01*
Y46096D01*
Y46042D01*
Y45988D01*
Y45933D01*
Y45880D01*
Y45825D01*
Y45771D01*
Y45717D01*
Y45663D01*
Y45609D01*
Y45555D01*
Y45501D01*
Y45447D01*
Y45393D01*
Y45339D01*
Y45285D01*
Y45231D01*
Y45177D01*
Y45123D01*
Y45068D01*
Y45015D01*
Y44960D01*
Y44906D01*
Y44852D01*
Y44798D01*
Y44744D01*
Y44690D01*
Y44636D01*
Y44582D01*
Y44528D01*
Y44474D01*
Y44420D01*
Y44366D01*
Y44312D01*
Y44258D01*
Y44204D01*
Y44150D01*
Y44095D01*
Y44041D01*
Y43987D01*
Y43933D01*
Y43879D01*
Y43825D01*
Y43771D01*
Y43717D01*
Y43663D01*
Y43609D01*
Y43555D01*
Y43501D01*
Y43447D01*
Y43393D01*
Y43339D01*
Y43284D01*
Y43230D01*
Y43176D01*
Y43122D01*
Y43068D01*
Y43014D01*
Y42960D01*
Y42906D01*
Y42852D01*
Y42798D01*
Y42744D01*
Y42690D01*
Y42636D01*
Y42582D01*
Y42528D01*
Y42474D01*
Y42419D01*
Y42365D01*
Y42311D01*
Y42257D01*
Y42203D01*
Y42149D01*
Y42095D01*
Y42041D01*
Y41987D01*
Y41933D01*
Y41879D01*
Y41825D01*
Y41771D01*
Y41717D01*
Y41663D01*
Y41609D01*
Y41554D01*
Y41500D01*
Y41446D01*
Y41392D01*
Y41338D01*
Y41284D01*
Y41230D01*
Y41176D01*
Y41122D01*
Y41068D01*
Y41014D01*
Y40960D01*
Y40906D01*
Y40852D01*
Y40798D01*
Y40744D01*
Y40690D01*
Y40635D01*
Y40581D01*
Y40527D01*
Y40473D01*
Y40419D01*
Y40365D01*
Y40311D01*
Y40257D01*
Y40203D01*
Y40149D01*
Y40095D01*
Y40041D01*
X94078D01*
Y39987D01*
Y39933D01*
Y39879D01*
Y39825D01*
Y39770D01*
X94024D01*
Y39716D01*
Y39662D01*
Y39608D01*
Y39554D01*
X93970D01*
Y39500D01*
Y39446D01*
X93916D01*
Y39392D01*
Y39338D01*
Y39284D01*
X93862D01*
Y39230D01*
Y39176D01*
X93808D01*
Y39122D01*
Y39068D01*
X93754D01*
Y39014D01*
Y38960D01*
X93700D01*
Y38906D01*
Y38851D01*
X93646D01*
Y38797D01*
X93592D01*
Y38743D01*
Y38689D01*
X93538D01*
Y38635D01*
X93484D01*
Y38581D01*
X93430D01*
Y38527D01*
Y38473D01*
X93375D01*
Y38419D01*
X93321D01*
Y38365D01*
X93267D01*
Y38311D01*
X93213D01*
Y38257D01*
X93159D01*
Y38203D01*
X93105D01*
Y38149D01*
X93051D01*
Y38094D01*
X92997D01*
Y38041D01*
X92889D01*
Y37986D01*
X92835D01*
Y37932D01*
X92781D01*
Y37878D01*
X92673D01*
Y37824D01*
X92619D01*
Y37770D01*
X92510D01*
Y37716D01*
X92402D01*
Y37662D01*
X92294D01*
Y37608D01*
X92186D01*
Y37554D01*
X92024D01*
Y37500D01*
X91916D01*
Y37446D01*
X91700D01*
Y37392D01*
X91483D01*
Y37338D01*
X90943D01*
Y37284D01*
X84077D01*
Y37338D01*
Y37392D01*
Y37446D01*
Y37500D01*
Y37554D01*
Y37608D01*
Y37662D01*
Y37716D01*
Y37770D01*
Y37824D01*
Y37878D01*
Y37932D01*
Y37986D01*
Y38041D01*
Y38094D01*
Y38149D01*
Y38203D01*
Y38257D01*
Y38311D01*
Y38365D01*
Y38419D01*
Y38473D01*
Y38527D01*
Y38581D01*
Y38635D01*
Y38689D01*
Y38743D01*
Y38797D01*
Y38851D01*
Y38906D01*
Y38960D01*
Y39014D01*
Y39068D01*
Y39122D01*
Y39176D01*
Y39230D01*
Y39284D01*
Y39338D01*
X90943D01*
Y39392D01*
X91159D01*
Y39446D01*
X91267D01*
Y39500D01*
X91375D01*
Y39554D01*
X91483D01*
Y39608D01*
X91537D01*
Y39662D01*
X91645D01*
Y39716D01*
X91700D01*
Y39770D01*
X91754D01*
Y39825D01*
X91808D01*
Y39879D01*
Y39933D01*
X91862D01*
Y39987D01*
X91916D01*
Y40041D01*
Y40095D01*
X91970D01*
Y40149D01*
Y40203D01*
X92024D01*
Y40257D01*
Y40311D01*
X92078D01*
Y40365D01*
Y40419D01*
Y40473D01*
Y40527D01*
Y40581D01*
X92132D01*
Y40635D01*
Y40690D01*
Y40744D01*
Y40798D01*
Y40852D01*
Y40906D01*
Y40960D01*
Y41014D01*
Y41068D01*
Y41122D01*
Y41176D01*
Y41230D01*
Y41284D01*
Y41338D01*
Y41392D01*
Y41446D01*
Y41500D01*
Y41554D01*
Y41609D01*
Y41663D01*
Y41717D01*
Y41771D01*
Y41825D01*
Y41879D01*
Y41933D01*
Y41987D01*
Y42041D01*
Y42095D01*
Y42149D01*
Y42203D01*
Y42257D01*
Y42311D01*
Y42365D01*
Y42419D01*
Y42474D01*
Y42528D01*
Y42582D01*
Y42636D01*
Y42690D01*
Y42744D01*
Y42798D01*
Y42852D01*
Y42906D01*
Y42960D01*
Y43014D01*
Y43068D01*
Y43122D01*
Y43176D01*
Y43230D01*
Y43284D01*
Y43339D01*
Y43393D01*
Y43447D01*
Y43501D01*
Y43555D01*
Y43609D01*
Y43663D01*
Y43717D01*
Y43771D01*
Y43825D01*
Y43879D01*
Y43933D01*
Y43987D01*
Y44041D01*
Y44095D01*
Y44150D01*
Y44204D01*
Y44258D01*
Y44312D01*
Y44366D01*
Y44420D01*
Y44474D01*
Y44528D01*
Y44582D01*
Y44636D01*
Y44690D01*
Y44744D01*
Y44798D01*
Y44852D01*
Y44906D01*
Y44960D01*
Y45015D01*
Y45068D01*
Y45123D01*
Y45177D01*
Y45231D01*
Y45285D01*
Y45339D01*
Y45393D01*
Y45447D01*
Y45501D01*
Y45555D01*
Y45609D01*
Y45663D01*
Y45717D01*
Y45771D01*
Y45825D01*
Y45880D01*
Y45933D01*
Y45988D01*
Y46042D01*
Y46096D01*
Y46150D01*
Y46204D01*
Y46258D01*
Y46312D01*
Y46366D01*
Y46420D01*
Y46474D01*
Y46528D01*
Y46582D01*
Y46636D01*
Y46690D01*
Y46744D01*
Y46799D01*
Y46853D01*
Y46907D01*
Y46961D01*
Y47015D01*
Y47069D01*
Y47123D01*
Y47177D01*
Y47231D01*
Y47285D01*
Y47339D01*
Y47393D01*
Y47447D01*
Y47501D01*
Y47555D01*
Y47609D01*
Y47664D01*
Y47718D01*
Y47772D01*
Y47826D01*
Y47880D01*
Y47934D01*
Y47988D01*
Y48042D01*
Y48096D01*
Y48150D01*
Y48204D01*
Y48258D01*
Y48312D01*
Y48366D01*
Y48420D01*
Y48474D01*
Y48529D01*
Y48583D01*
Y48637D01*
Y48691D01*
Y48745D01*
Y48799D01*
Y48853D01*
Y48907D01*
Y48961D01*
Y49015D01*
Y49069D01*
Y49123D01*
Y49177D01*
Y49231D01*
Y49285D01*
Y49339D01*
Y49393D01*
Y49448D01*
Y49502D01*
Y49556D01*
Y49610D01*
Y49664D01*
Y49718D01*
Y49772D01*
Y49826D01*
Y49880D01*
Y49934D01*
Y49988D01*
Y50042D01*
Y50096D01*
Y50150D01*
Y50204D01*
Y50258D01*
Y50313D01*
Y50367D01*
Y50421D01*
Y50475D01*
Y50529D01*
Y50583D01*
Y50637D01*
Y50691D01*
Y50745D01*
Y50799D01*
Y50853D01*
Y50907D01*
Y50961D01*
Y51015D01*
Y51069D01*
Y51123D01*
Y51178D01*
Y51232D01*
Y51286D01*
Y51340D01*
Y51394D01*
Y51448D01*
Y51502D01*
Y51556D01*
Y51610D01*
Y51664D01*
Y51718D01*
Y51772D01*
Y51826D01*
Y51880D01*
Y51934D01*
Y51989D01*
Y52043D01*
Y52097D01*
Y52151D01*
Y52205D01*
Y52259D01*
Y52313D01*
Y52367D01*
Y52421D01*
Y52475D01*
Y52529D01*
Y52583D01*
Y52637D01*
Y52691D01*
Y52745D01*
Y52799D01*
Y52854D01*
Y52908D01*
Y52962D01*
Y53016D01*
Y53070D01*
Y53124D01*
Y53178D01*
Y53232D01*
Y53286D01*
Y53340D01*
Y53394D01*
Y53448D01*
Y53502D01*
Y53556D01*
Y53610D01*
Y53664D01*
Y53719D01*
Y53772D01*
Y53827D01*
Y53881D01*
Y53935D01*
Y53989D01*
Y54043D01*
Y54097D01*
Y54151D01*
Y54205D01*
Y54259D01*
Y54313D01*
Y54367D01*
Y54421D01*
Y54475D01*
Y54529D01*
Y54584D01*
Y54637D01*
Y54692D01*
Y54746D01*
Y54800D01*
Y54854D01*
Y54908D01*
Y54962D01*
Y55016D01*
Y55070D01*
Y55124D01*
Y55178D01*
Y55232D01*
Y55286D01*
Y55340D01*
Y55394D01*
Y55449D01*
Y55502D01*
Y55557D01*
Y55611D01*
Y55665D01*
Y55719D01*
Y55773D01*
Y55827D01*
Y55881D01*
Y55935D01*
Y55989D01*
Y56043D01*
Y56097D01*
Y56151D01*
Y56205D01*
Y56259D01*
Y56313D01*
Y56367D01*
Y56422D01*
Y56476D01*
Y56530D01*
Y56584D01*
Y56638D01*
Y56692D01*
Y56746D01*
Y56800D01*
Y56854D01*
Y56908D01*
Y56962D01*
Y57016D01*
Y57070D01*
Y57124D01*
Y57178D01*
Y57232D01*
Y57287D01*
Y57341D01*
Y57395D01*
Y57449D01*
Y57503D01*
Y57557D01*
Y57611D01*
Y57665D01*
Y57719D01*
Y57773D01*
Y57827D01*
Y57881D01*
Y57935D01*
Y57989D01*
Y58043D01*
Y58097D01*
Y58152D01*
Y58206D01*
Y58260D01*
Y58314D01*
Y58368D01*
Y58422D01*
Y58476D01*
Y58530D01*
Y58584D01*
Y58638D01*
Y58692D01*
Y58746D01*
Y58800D01*
Y58854D01*
Y58908D01*
Y58963D01*
Y59017D01*
Y59071D01*
Y59125D01*
Y59179D01*
Y59233D01*
Y59287D01*
Y59341D01*
Y59395D01*
Y59449D01*
Y59503D01*
Y59557D01*
Y59611D01*
Y59665D01*
Y59719D01*
Y59773D01*
Y59828D01*
Y59882D01*
Y59936D01*
Y59990D01*
Y60044D01*
Y60098D01*
Y60152D01*
Y60206D01*
Y60260D01*
Y60314D01*
Y60368D01*
Y60422D01*
Y60476D01*
Y60530D01*
Y60584D01*
Y60638D01*
Y60693D01*
Y60747D01*
Y60801D01*
Y60855D01*
Y60909D01*
Y60963D01*
Y61017D01*
Y61071D01*
Y61125D01*
Y61179D01*
Y61233D01*
Y61287D01*
Y61341D01*
Y61395D01*
Y61449D01*
Y61503D01*
Y61557D01*
Y61611D01*
Y61666D01*
Y61720D01*
Y61774D01*
Y61828D01*
Y61882D01*
Y61936D01*
Y61990D01*
Y62044D01*
Y62098D01*
Y62152D01*
Y62206D01*
Y62260D01*
Y62314D01*
Y62368D01*
Y62423D01*
Y62476D01*
Y62531D01*
Y62585D01*
Y62639D01*
Y62693D01*
Y62747D01*
Y62801D01*
Y62855D01*
Y62909D01*
Y62963D01*
Y63017D01*
Y63071D01*
Y63125D01*
Y63179D01*
Y63233D01*
Y63287D01*
Y63341D01*
Y63396D01*
Y63450D01*
Y63504D01*
Y63558D01*
Y63612D01*
Y63666D01*
Y63720D01*
Y63774D01*
Y63828D01*
Y63882D01*
Y63936D01*
Y63990D01*
Y64044D01*
Y64098D01*
Y64152D01*
Y64206D01*
Y64261D01*
Y64315D01*
Y64369D01*
Y64423D01*
Y64477D01*
Y64531D01*
Y64585D01*
Y64639D01*
Y64693D01*
Y64747D01*
Y64801D01*
Y64855D01*
Y64909D01*
Y64963D01*
Y65017D01*
Y65071D01*
Y65126D01*
Y65180D01*
Y65234D01*
Y65288D01*
Y65342D01*
Y65396D01*
Y65450D01*
Y65504D01*
Y65558D01*
Y65612D01*
Y65666D01*
Y65720D01*
Y65774D01*
Y65828D01*
Y65882D01*
Y65936D01*
Y65991D01*
Y66045D01*
Y66099D01*
Y66153D01*
Y66207D01*
Y66261D01*
Y66315D01*
Y66369D01*
Y66423D01*
Y66477D01*
Y66531D01*
Y66585D01*
Y66639D01*
Y66693D01*
Y66747D01*
Y66802D01*
Y66856D01*
Y66910D01*
Y66964D01*
Y67018D01*
Y67072D01*
Y67126D01*
Y67180D01*
Y67234D01*
Y67288D01*
Y67342D01*
Y67396D01*
Y67450D01*
Y67504D01*
Y67558D01*
Y67612D01*
Y67667D01*
Y67721D01*
Y67775D01*
Y67829D01*
Y67883D01*
Y67937D01*
Y67991D01*
Y68045D01*
Y68099D01*
Y68153D01*
Y68207D01*
Y68261D01*
Y68315D01*
Y68369D01*
Y68423D01*
Y68477D01*
Y68531D01*
Y68585D01*
Y68640D01*
Y68694D01*
Y68748D01*
Y68802D01*
Y68856D01*
Y68910D01*
Y68964D01*
Y69018D01*
Y69072D01*
Y69126D01*
Y69180D01*
Y69234D01*
Y69288D01*
Y69342D01*
Y69397D01*
Y69450D01*
Y69505D01*
Y69559D01*
Y69613D01*
Y69667D01*
Y69721D01*
Y69775D01*
Y69829D01*
Y69883D01*
Y69937D01*
Y69991D01*
Y70045D01*
Y70099D01*
Y70153D01*
Y70207D01*
Y70261D01*
Y70315D01*
Y70370D01*
Y70424D01*
Y70478D01*
Y70532D01*
Y70586D01*
Y70640D01*
Y70694D01*
Y70748D01*
Y70802D01*
Y70856D01*
Y70910D01*
Y70964D01*
Y71018D01*
Y71072D01*
Y71126D01*
Y71180D01*
Y71235D01*
Y71289D01*
Y71343D01*
Y71397D01*
Y71451D01*
Y71505D01*
Y71559D01*
Y71613D01*
Y71667D01*
Y71721D01*
Y71775D01*
Y71829D01*
Y71883D01*
Y71937D01*
Y71991D01*
Y72045D01*
Y72100D01*
Y72154D01*
Y72208D01*
Y72262D01*
Y72316D01*
Y72370D01*
Y72424D01*
Y72478D01*
Y72532D01*
Y72586D01*
Y72640D01*
Y72694D01*
Y72748D01*
Y72802D01*
Y72856D01*
Y72910D01*
Y72965D01*
Y73019D01*
Y73073D01*
Y73127D01*
Y73181D01*
Y73235D01*
Y73289D01*
Y73343D01*
Y73397D01*
Y73451D01*
Y73505D01*
Y73559D01*
Y73613D01*
Y73667D01*
Y73721D01*
Y73776D01*
Y73830D01*
Y73884D01*
Y73938D01*
Y73992D01*
Y74046D01*
Y74100D01*
Y74154D01*
Y74208D01*
Y74262D01*
Y74316D01*
Y74370D01*
Y74424D01*
Y74478D01*
Y74532D01*
Y74586D01*
Y74641D01*
Y74695D01*
Y74749D01*
Y74803D01*
Y74857D01*
Y74911D01*
Y74965D01*
Y75019D01*
Y75073D01*
Y75127D01*
Y75181D01*
Y75235D01*
Y75289D01*
Y75343D01*
Y75397D01*
Y75451D01*
Y75505D01*
Y75560D01*
Y75614D01*
Y75668D01*
Y75722D01*
Y75776D01*
Y75830D01*
Y75884D01*
Y75938D01*
Y75992D01*
Y76046D01*
Y76100D01*
Y76154D01*
Y76208D01*
Y76262D01*
Y76316D01*
Y76371D01*
Y76424D01*
Y76479D01*
Y76533D01*
Y76587D01*
Y76641D01*
Y76695D01*
Y76749D01*
Y76803D01*
Y76857D01*
Y76911D01*
Y76965D01*
Y77019D01*
Y77073D01*
Y77127D01*
Y77181D01*
Y77235D01*
Y77289D01*
Y77344D01*
Y77398D01*
Y77452D01*
Y77506D01*
Y77560D01*
Y77614D01*
Y77668D01*
Y77722D01*
Y77776D01*
Y77830D01*
Y77884D01*
Y77938D01*
Y77992D01*
Y78046D01*
Y78100D01*
Y78154D01*
Y78209D01*
Y78263D01*
Y78317D01*
Y78371D01*
Y78425D01*
Y78479D01*
Y78533D01*
Y78587D01*
Y78641D01*
Y78695D01*
Y78749D01*
Y78803D01*
Y78857D01*
Y78911D01*
Y78965D01*
Y79019D01*
Y79074D01*
Y79128D01*
Y79182D01*
Y79236D01*
Y79290D01*
Y79344D01*
Y79398D01*
Y79452D01*
Y79506D01*
Y79560D01*
Y79614D01*
Y79668D01*
Y79722D01*
Y79776D01*
Y79830D01*
Y79884D01*
Y79939D01*
Y79993D01*
Y80047D01*
Y80101D01*
Y80155D01*
Y80209D01*
Y80263D01*
Y80317D01*
Y80371D01*
Y80425D01*
Y80479D01*
Y80533D01*
Y80587D01*
Y80641D01*
Y80695D01*
Y80749D01*
Y80804D01*
Y80858D01*
Y80912D01*
Y80966D01*
Y81020D01*
Y81074D01*
Y81128D01*
Y81182D01*
Y81236D01*
Y81290D01*
Y81344D01*
Y81398D01*
Y81452D01*
Y81506D01*
Y81560D01*
Y81615D01*
Y81669D01*
Y81723D01*
Y81777D01*
Y81831D01*
Y81885D01*
Y81939D01*
Y81993D01*
Y82047D01*
Y82101D01*
Y82155D01*
Y82209D01*
Y82263D01*
Y82317D01*
Y82371D01*
Y82425D01*
Y82479D01*
Y82534D01*
Y82588D01*
Y82642D01*
Y82696D01*
Y82750D01*
Y82804D01*
Y82858D01*
Y82912D01*
Y82966D01*
Y83020D01*
Y83074D01*
Y83128D01*
Y83182D01*
Y83236D01*
Y83290D01*
Y83344D01*
Y83398D01*
Y83453D01*
Y83507D01*
Y83561D01*
Y83615D01*
Y83669D01*
Y83723D01*
Y83777D01*
Y83831D01*
Y83885D01*
Y83939D01*
Y83993D01*
Y84047D01*
Y84101D01*
Y84155D01*
Y84209D01*
Y84263D01*
Y84318D01*
Y84372D01*
Y84426D01*
Y84480D01*
Y84534D01*
Y84588D01*
Y84642D01*
Y84696D01*
Y84750D01*
Y84804D01*
Y84858D01*
Y84912D01*
Y84966D01*
Y85020D01*
Y85074D01*
Y85128D01*
Y85183D01*
Y85237D01*
Y85291D01*
Y85345D01*
Y85399D01*
Y85453D01*
Y85507D01*
Y85561D01*
Y85615D01*
Y85669D01*
Y85723D01*
Y85777D01*
Y85831D01*
Y85885D01*
Y85939D01*
Y85993D01*
Y86048D01*
Y86102D01*
Y86156D01*
Y86210D01*
Y86264D01*
Y86318D01*
Y86372D01*
Y86426D01*
Y86480D01*
Y86534D01*
Y86588D01*
Y86642D01*
Y86696D01*
Y86750D01*
Y86804D01*
Y86858D01*
Y86913D01*
Y86967D01*
Y87021D01*
Y87075D01*
Y87129D01*
Y87183D01*
Y87237D01*
Y87291D01*
Y87345D01*
Y87399D01*
Y87453D01*
Y87507D01*
Y87561D01*
Y87615D01*
Y87669D01*
Y87723D01*
Y87778D01*
Y87832D01*
Y87886D01*
Y87940D01*
Y87994D01*
Y88048D01*
Y88102D01*
Y88156D01*
Y88210D01*
Y88264D01*
Y88318D01*
Y88372D01*
Y88426D01*
Y88480D01*
Y88534D01*
Y88589D01*
Y88643D01*
Y88697D01*
Y88751D01*
Y88805D01*
Y88859D01*
Y88913D01*
Y88967D01*
Y89021D01*
Y89075D01*
Y89129D01*
Y89183D01*
Y89237D01*
Y89291D01*
Y89345D01*
Y89399D01*
Y89453D01*
Y89508D01*
Y89562D01*
Y89616D01*
Y89670D01*
Y89724D01*
Y89778D01*
Y89832D01*
Y89886D01*
Y89940D01*
Y89994D01*
Y90048D01*
Y90102D01*
Y90156D01*
Y90210D01*
Y90264D01*
Y90318D01*
Y90373D01*
Y90427D01*
Y90481D01*
Y90535D01*
Y90589D01*
Y90643D01*
Y90697D01*
Y90751D01*
Y90805D01*
Y90859D01*
Y90913D01*
Y90967D01*
Y91021D01*
Y91075D01*
Y91129D01*
Y91183D01*
Y91237D01*
Y91292D01*
Y91346D01*
Y91400D01*
Y91454D01*
Y91508D01*
Y91562D01*
Y91616D01*
Y91670D01*
Y91724D01*
Y91778D01*
Y91832D01*
Y91886D01*
Y91940D01*
Y91994D01*
Y92048D01*
Y92102D01*
Y92157D01*
Y92211D01*
Y92265D01*
Y92319D01*
Y92373D01*
Y92427D01*
Y92481D01*
Y92535D01*
Y92589D01*
Y92643D01*
Y92697D01*
Y92751D01*
Y92805D01*
Y92859D01*
Y92913D01*
Y92967D01*
Y93022D01*
Y93076D01*
Y93130D01*
Y93184D01*
Y93238D01*
Y93292D01*
Y93346D01*
Y93400D01*
Y93454D01*
Y93508D01*
Y93562D01*
Y93616D01*
Y93670D01*
Y93724D01*
Y93778D01*
Y93832D01*
Y93887D01*
Y93941D01*
Y93995D01*
Y94049D01*
Y94103D01*
Y94157D01*
Y94211D01*
Y94265D01*
Y94319D01*
Y94373D01*
Y94427D01*
Y94481D01*
Y94535D01*
Y94589D01*
Y94643D01*
Y94697D01*
Y94752D01*
Y94806D01*
Y94860D01*
Y94914D01*
Y94968D01*
Y95022D01*
Y95076D01*
Y95130D01*
Y95184D01*
Y95238D01*
Y95292D01*
Y95346D01*
Y95400D01*
Y95454D01*
Y95508D01*
Y95562D01*
Y95617D01*
Y95671D01*
Y95725D01*
Y95779D01*
Y95833D01*
Y95887D01*
Y95941D01*
Y95995D01*
Y96049D01*
Y96103D01*
Y96157D01*
Y96211D01*
Y96265D01*
Y96319D01*
Y96373D01*
Y96427D01*
Y96482D01*
Y96536D01*
Y96590D01*
Y96644D01*
Y96698D01*
Y96752D01*
Y96806D01*
Y96860D01*
Y96914D01*
Y96968D01*
Y97022D01*
Y97076D01*
Y97130D01*
Y97184D01*
Y97238D01*
Y97292D01*
Y97347D01*
Y97401D01*
Y97455D01*
Y97509D01*
Y97563D01*
Y97617D01*
Y97671D01*
Y97725D01*
Y97779D01*
Y97833D01*
Y97887D01*
Y97941D01*
Y97995D01*
Y98049D01*
Y98103D01*
Y98157D01*
Y98211D01*
Y98266D01*
Y98320D01*
Y98374D01*
Y98428D01*
Y98482D01*
Y98536D01*
Y98590D01*
Y98644D01*
Y98698D01*
Y98752D01*
Y98806D01*
Y98860D01*
Y98914D01*
Y98968D01*
Y99022D01*
Y99076D01*
X94132D01*
Y99022D01*
D02*
G37*
%LPC*%
G36*
X28810Y96808D02*
X28799D01*
Y96797D01*
X28810D01*
Y96808D01*
D02*
G37*
G36*
X28741Y96785D02*
X28730D01*
Y96773D01*
X28741D01*
Y96785D01*
D02*
G37*
G36*
Y96716D02*
X28730D01*
Y96704D01*
X28741D01*
Y96716D01*
D02*
G37*
G36*
X28706D02*
X28695D01*
Y96704D01*
Y96681D01*
X28706D01*
Y96716D01*
D02*
G37*
G36*
X28465Y96382D02*
X28453D01*
Y96370D01*
X28465D01*
Y96382D01*
D02*
G37*
G36*
X28948D02*
X28937D01*
Y96347D01*
X28960D01*
Y96370D01*
X28948D01*
Y96382D01*
D02*
G37*
G36*
X28465Y96347D02*
X28453D01*
Y96324D01*
X28465D01*
Y96347D01*
D02*
G37*
G36*
X28557Y96324D02*
X28545D01*
Y96313D01*
X28557D01*
Y96324D01*
D02*
G37*
G36*
X28465Y96290D02*
X28453D01*
Y96278D01*
X28465D01*
Y96290D01*
D02*
G37*
G36*
X28384D02*
X28372D01*
Y96278D01*
X28384D01*
Y96290D01*
D02*
G37*
G36*
X28971Y96267D02*
X28960D01*
Y96255D01*
X28971D01*
Y96267D01*
D02*
G37*
G36*
X28465D02*
X28453D01*
Y96244D01*
X28465D01*
Y96232D01*
X28476D01*
Y96255D01*
X28465D01*
Y96267D01*
D02*
G37*
G36*
X28476Y96209D02*
X28465D01*
Y96186D01*
X28476D01*
Y96209D01*
D02*
G37*
G36*
X28326Y96221D02*
X28315D01*
Y96163D01*
X28326D01*
Y96221D01*
D02*
G37*
G36*
X28419Y96278D02*
X28407D01*
Y96267D01*
X28384D01*
Y96244D01*
X28372D01*
Y96221D01*
X28384D01*
Y96117D01*
X28372D01*
Y96105D01*
X28384D01*
Y96071D01*
X28396D01*
Y96048D01*
X28419D01*
Y96105D01*
X28465D01*
Y96163D01*
X28453D01*
Y96198D01*
X28419D01*
Y96221D01*
Y96232D01*
X28407D01*
Y96244D01*
X28419D01*
Y96278D01*
D02*
G37*
G36*
X28453Y96048D02*
X28442D01*
Y96036D01*
X28453D01*
Y96048D01*
D02*
G37*
G36*
X28856Y95956D02*
X28845D01*
Y95944D01*
X28856D01*
Y95956D01*
D02*
G37*
G36*
X28234D02*
X28223D01*
Y95933D01*
X28234D01*
Y95944D01*
Y95956D01*
D02*
G37*
G36*
X27992Y95898D02*
X27981D01*
Y95887D01*
X27992D01*
Y95898D01*
D02*
G37*
G36*
X28879Y95864D02*
X28856D01*
Y95829D01*
X28868D01*
Y95818D01*
X28879D01*
Y95841D01*
Y95852D01*
Y95864D01*
D02*
G37*
G36*
X28004Y95818D02*
X27992D01*
Y95806D01*
X28004D01*
Y95818D01*
D02*
G37*
G36*
Y95760D02*
X27992D01*
Y95714D01*
X28004D01*
Y95725D01*
X28016D01*
Y95737D01*
X28004D01*
Y95760D01*
D02*
G37*
G36*
X28027Y95702D02*
X28004D01*
Y95691D01*
X28027D01*
Y95702D01*
D02*
G37*
G36*
X28004Y95656D02*
X27992D01*
Y95645D01*
X28004D01*
Y95656D01*
D02*
G37*
G36*
X29029Y95576D02*
X29017D01*
Y95564D01*
X29029D01*
Y95576D01*
D02*
G37*
G36*
X28879Y95806D02*
X28868D01*
Y95760D01*
X28879D01*
Y95668D01*
X28891D01*
Y95633D01*
Y95622D01*
Y95576D01*
X28902D01*
Y95553D01*
X28925D01*
Y95576D01*
X28914D01*
Y95679D01*
X28902D01*
Y95691D01*
X28891D01*
Y95794D01*
X28879D01*
Y95806D01*
D02*
G37*
G36*
X28925Y95530D02*
X28902D01*
Y95495D01*
X28925D01*
Y95507D01*
Y95518D01*
Y95530D01*
D02*
G37*
G36*
X29063Y95472D02*
X29052D01*
Y95461D01*
X29063D01*
Y95472D01*
D02*
G37*
G36*
X27912Y95438D02*
X27900D01*
Y95426D01*
X27912D01*
Y95438D01*
D02*
G37*
G36*
X29075Y95426D02*
X29063D01*
Y95415D01*
X29075D01*
Y95426D01*
D02*
G37*
G36*
X28799Y95415D02*
X28787D01*
Y95391D01*
X28799D01*
Y95415D01*
D02*
G37*
G36*
X29075Y95380D02*
X29063D01*
Y95368D01*
X29075D01*
Y95380D01*
D02*
G37*
G36*
X28787Y95368D02*
X28776D01*
Y95357D01*
X28764D01*
Y95345D01*
X28776D01*
Y95334D01*
X28799D01*
Y95357D01*
X28787D01*
Y95368D01*
D02*
G37*
G36*
X28810Y95322D02*
X28799D01*
Y95311D01*
X28787D01*
Y95288D01*
X28810D01*
Y95299D01*
X28822D01*
Y95311D01*
X28810D01*
Y95322D01*
D02*
G37*
G36*
X27946Y95633D02*
X27923D01*
Y95599D01*
X27935D01*
Y95299D01*
X27946D01*
Y95276D01*
X27958D01*
Y95322D01*
X27969D01*
Y95334D01*
X27958D01*
Y95368D01*
X27969D01*
Y95380D01*
X27981D01*
Y95391D01*
X27969D01*
Y95403D01*
X27958D01*
Y95449D01*
X27969D01*
Y95461D01*
X27981D01*
Y95472D01*
X27969D01*
Y95484D01*
X27958D01*
Y95495D01*
X27969D01*
Y95507D01*
X27981D01*
Y95541D01*
X27946D01*
Y95622D01*
Y95633D01*
D02*
G37*
G36*
X27981Y95265D02*
X27958D01*
Y95253D01*
X27946D01*
Y95230D01*
X27992D01*
Y95253D01*
X27981D01*
Y95265D01*
D02*
G37*
G36*
X28027Y95242D02*
X28004D01*
Y95219D01*
X28027D01*
Y95242D01*
D02*
G37*
G36*
X28833Y95196D02*
X28822D01*
Y95184D01*
X28833D01*
Y95196D01*
D02*
G37*
G36*
X27992D02*
X27981D01*
Y95184D01*
X27992D01*
Y95196D01*
D02*
G37*
G36*
Y95161D02*
X27981D01*
Y95138D01*
X27992D01*
Y95161D01*
D02*
G37*
G36*
X27946Y95138D02*
X27935D01*
Y95115D01*
X27946D01*
Y95127D01*
Y95138D01*
D02*
G37*
G36*
X28925Y95115D02*
X28914D01*
Y95104D01*
X28925D01*
Y95115D01*
D02*
G37*
G36*
X29121Y95092D02*
X29110D01*
Y95081D01*
X29121D01*
Y95092D01*
D02*
G37*
G36*
X28004D02*
X27992D01*
Y95057D01*
Y95046D01*
X28004D01*
Y95092D01*
D02*
G37*
G36*
Y95023D02*
X27992D01*
Y95011D01*
X28004D01*
Y95023D01*
D02*
G37*
G36*
X28591Y95011D02*
X28568D01*
Y95000D01*
X28591D01*
Y95011D01*
D02*
G37*
G36*
X28937Y95000D02*
X28925D01*
Y94988D01*
X28937D01*
Y95000D01*
D02*
G37*
G36*
X28856D02*
X28845D01*
Y94954D01*
X28868D01*
Y94965D01*
Y94988D01*
X28856D01*
Y95000D01*
D02*
G37*
G36*
X27946Y94965D02*
X27935D01*
Y94942D01*
X27946D01*
Y94965D01*
D02*
G37*
G36*
X28004Y94942D02*
X27992D01*
Y94919D01*
X28004D01*
Y94931D01*
Y94942D01*
D02*
G37*
G36*
X27589Y94919D02*
X27578D01*
Y94908D01*
X27589D01*
Y94919D01*
D02*
G37*
G36*
X28879D02*
X28868D01*
Y94908D01*
X28879D01*
Y94919D01*
D02*
G37*
G36*
X30756Y94954D02*
X30733D01*
Y94885D01*
X30756D01*
Y94942D01*
Y94954D01*
D02*
G37*
G36*
X28845Y94896D02*
X28833D01*
Y94885D01*
X28845D01*
Y94896D01*
D02*
G37*
G36*
X28649Y94908D02*
X28637D01*
Y94873D01*
X28649D01*
Y94885D01*
Y94896D01*
Y94908D01*
D02*
G37*
G36*
X27405Y94919D02*
X27382D01*
Y94873D01*
X27394D01*
Y94885D01*
X27405D01*
Y94896D01*
Y94919D01*
D02*
G37*
G36*
X29133Y94896D02*
X29121D01*
Y94873D01*
Y94862D01*
X29133D01*
Y94896D01*
D02*
G37*
G36*
X29121Y94862D02*
X29110D01*
Y94850D01*
X29121D01*
Y94862D01*
D02*
G37*
G36*
X28879Y94873D02*
X28856D01*
Y94862D01*
X28868D01*
Y94850D01*
X28879D01*
Y94873D01*
D02*
G37*
G36*
X27497Y94850D02*
X27486D01*
Y94839D01*
X27497D01*
Y94850D01*
D02*
G37*
G36*
X30618Y94827D02*
X30607D01*
Y94816D01*
X30618D01*
Y94827D01*
D02*
G37*
G36*
X28856Y94804D02*
X28845D01*
Y94793D01*
X28856D01*
Y94804D01*
D02*
G37*
G36*
X28660Y94827D02*
X28649D01*
Y94816D01*
Y94770D01*
X28660D01*
Y94827D01*
D02*
G37*
G36*
X27463Y94758D02*
X27440D01*
Y94747D01*
X27463D01*
Y94758D01*
D02*
G37*
G36*
X30538D02*
X30526D01*
Y94735D01*
Y94723D01*
X30538D01*
Y94758D01*
D02*
G37*
G36*
X28891Y94723D02*
X28879D01*
Y94712D01*
X28891D01*
Y94723D01*
D02*
G37*
G36*
X28971Y94735D02*
X28948D01*
Y94723D01*
Y94712D01*
Y94700D01*
X28971D01*
Y94735D01*
D02*
G37*
G36*
X30492Y94677D02*
X30480D01*
Y94666D01*
X30492D01*
Y94677D01*
D02*
G37*
G36*
X28902D02*
X28891D01*
Y94666D01*
X28902D01*
Y94677D01*
D02*
G37*
G36*
X28637D02*
X28614D01*
Y94666D01*
X28637D01*
Y94677D01*
D02*
G37*
G36*
X27601Y94689D02*
X27578D01*
Y94666D01*
X27601D01*
Y94689D01*
D02*
G37*
G36*
X27152Y94643D02*
X27140D01*
Y94631D01*
X27152D01*
Y94643D01*
D02*
G37*
G36*
X30434Y94631D02*
X30422D01*
Y94620D01*
X30434D01*
Y94631D01*
D02*
G37*
G36*
X29133D02*
X29121D01*
Y94620D01*
X29133D01*
Y94631D01*
D02*
G37*
G36*
X28649D02*
X28637D01*
Y94608D01*
X28649D01*
Y94620D01*
Y94631D01*
D02*
G37*
G36*
X28971Y94620D02*
X28937D01*
Y94608D01*
X28948D01*
Y94597D01*
X28960D01*
Y94608D01*
X28971D01*
Y94620D01*
D02*
G37*
G36*
X30434Y94597D02*
X30422D01*
Y94585D01*
X30434D01*
Y94597D01*
D02*
G37*
G36*
X27578Y94585D02*
X27566D01*
Y94574D01*
X27578D01*
Y94585D01*
D02*
G37*
G36*
X30399Y94574D02*
X30388D01*
Y94562D01*
X30399D01*
Y94574D01*
D02*
G37*
G36*
X28649D02*
X28637D01*
Y94562D01*
X28626D01*
Y94551D01*
X28637D01*
Y94539D01*
X28649D01*
Y94574D01*
D02*
G37*
G36*
X30307Y94459D02*
X30296D01*
Y94447D01*
X30307D01*
Y94459D01*
D02*
G37*
G36*
X28706Y94493D02*
X28695D01*
Y94447D01*
X28706D01*
Y94470D01*
Y94482D01*
Y94493D01*
D02*
G37*
G36*
X28660Y94505D02*
X28649D01*
Y94447D01*
X28660D01*
Y94482D01*
Y94493D01*
Y94505D01*
D02*
G37*
G36*
X29167Y94482D02*
X29156D01*
Y94470D01*
X29144D01*
Y94459D01*
X29156D01*
Y94436D01*
X29167D01*
Y94482D01*
D02*
G37*
G36*
X29017Y94447D02*
X28994D01*
Y94436D01*
X29017D01*
Y94447D01*
D02*
G37*
G36*
X28649Y94436D02*
X28637D01*
Y94424D01*
X28649D01*
Y94436D01*
D02*
G37*
G36*
X29029Y94389D02*
X29017D01*
Y94378D01*
X29029D01*
Y94389D01*
D02*
G37*
G36*
X28684Y94401D02*
X28660D01*
Y94378D01*
X28684D01*
Y94401D01*
D02*
G37*
G36*
X28718Y94355D02*
X28706D01*
Y94343D01*
X28718D01*
Y94355D01*
D02*
G37*
G36*
X27624Y94424D02*
X27612D01*
Y94389D01*
X27624D01*
Y94343D01*
X27647D01*
Y94355D01*
Y94401D01*
X27635D01*
Y94412D01*
X27624D01*
Y94424D01*
D02*
G37*
G36*
X27659Y94332D02*
X27647D01*
Y94320D01*
Y94309D01*
X27659D01*
Y94332D01*
D02*
G37*
G36*
X29063Y94297D02*
X29052D01*
Y94286D01*
X29063D01*
Y94297D01*
D02*
G37*
G36*
X26967D02*
X26956D01*
Y94286D01*
X26967D01*
Y94297D01*
D02*
G37*
G36*
X29029D02*
X29017D01*
Y94263D01*
X29029D01*
Y94286D01*
Y94297D01*
D02*
G37*
G36*
X28753Y94251D02*
X28730D01*
Y94240D01*
X28753D01*
Y94251D01*
D02*
G37*
G36*
X28706D02*
X28684D01*
Y94240D01*
X28672D01*
Y94205D01*
X28684D01*
Y94194D01*
X28695D01*
Y94217D01*
X28706D01*
Y94205D01*
X28718D01*
Y94228D01*
X28706D01*
Y94251D01*
D02*
G37*
G36*
X29110Y94182D02*
X29098D01*
Y94171D01*
X29087D01*
Y94159D01*
X29121D01*
Y94171D01*
X29110D01*
Y94182D01*
D02*
G37*
G36*
X28994Y94263D02*
X28983D01*
Y94228D01*
X28994D01*
Y94194D01*
X29017D01*
Y94205D01*
X29029D01*
Y94159D01*
X29041D01*
Y94171D01*
X29052D01*
Y94217D01*
X29041D01*
Y94240D01*
X29029D01*
Y94228D01*
X29006D01*
Y94251D01*
X28994D01*
Y94263D01*
D02*
G37*
G36*
X27681Y94194D02*
X27670D01*
Y94159D01*
X27681D01*
Y94171D01*
X27693D01*
Y94182D01*
X27681D01*
Y94194D01*
D02*
G37*
G36*
X28730Y94159D02*
X28706D01*
Y94148D01*
X28695D01*
Y94159D01*
X28684D01*
Y94148D01*
Y94136D01*
Y94125D01*
X28706D01*
Y94055D01*
X28741D01*
Y94113D01*
X28730D01*
Y94159D01*
D02*
G37*
G36*
X28660D02*
X28649D01*
Y94148D01*
X28660D01*
Y94159D01*
D02*
G37*
G36*
X27681Y94148D02*
X27670D01*
Y94136D01*
X27681D01*
Y94148D01*
D02*
G37*
G36*
X29121Y94125D02*
X29110D01*
Y94113D01*
X29121D01*
Y94125D01*
D02*
G37*
G36*
X27716Y94136D02*
X27705D01*
Y94125D01*
Y94113D01*
X27716D01*
Y94136D01*
D02*
G37*
G36*
X29017Y94171D02*
X28994D01*
Y94102D01*
X29006D01*
Y94090D01*
X29029D01*
Y94136D01*
X29017D01*
Y94171D01*
D02*
G37*
G36*
X27705Y94102D02*
X27693D01*
Y94090D01*
Y94079D01*
X27705D01*
Y94102D01*
D02*
G37*
G36*
X29927Y94079D02*
X29916D01*
Y94067D01*
X29927D01*
Y94079D01*
D02*
G37*
G36*
X26668D02*
X26656D01*
Y94067D01*
X26668D01*
Y94079D01*
D02*
G37*
G36*
X29121Y94102D02*
X29110D01*
Y94055D01*
X29133D01*
Y94090D01*
X29121D01*
Y94102D01*
D02*
G37*
G36*
X29063Y94136D02*
X29041D01*
Y94125D01*
Y94113D01*
Y94090D01*
X29052D01*
Y94079D01*
X29063D01*
Y94055D01*
X29075D01*
Y94067D01*
X29087D01*
Y94079D01*
X29098D01*
Y94090D01*
X29087D01*
Y94113D01*
X29075D01*
Y94090D01*
X29063D01*
Y94136D01*
D02*
G37*
G36*
X28787Y94079D02*
X28776D01*
Y94055D01*
X28787D01*
Y94067D01*
Y94079D01*
D02*
G37*
G36*
X29029Y94067D02*
X29017D01*
Y94044D01*
X29029D01*
Y94055D01*
Y94067D01*
D02*
G37*
G36*
X27566Y94055D02*
X27555D01*
Y94044D01*
X27566D01*
Y94055D01*
D02*
G37*
G36*
X29087Y94033D02*
X29075D01*
Y94021D01*
X29087D01*
Y94033D01*
D02*
G37*
G36*
X29133Y94021D02*
X29121D01*
Y94010D01*
X29133D01*
Y94021D01*
D02*
G37*
G36*
X28776Y94033D02*
X28753D01*
Y94010D01*
X28776D01*
Y94021D01*
Y94033D01*
D02*
G37*
G36*
X28706Y94055D02*
X28695D01*
Y94044D01*
X28706D01*
Y94010D01*
X28741D01*
Y94021D01*
X28730D01*
Y94033D01*
X28718D01*
Y94044D01*
X28706D01*
Y94055D01*
D02*
G37*
G36*
X26783Y94044D02*
X26772D01*
Y94033D01*
Y94010D01*
X26795D01*
Y94033D01*
X26783D01*
Y94044D01*
D02*
G37*
G36*
X27751Y94010D02*
X27728D01*
Y93986D01*
X27739D01*
Y93975D01*
X27751D01*
Y94010D01*
D02*
G37*
G36*
X29041Y93963D02*
X29029D01*
Y93952D01*
X29041D01*
Y93963D01*
D02*
G37*
G36*
X29144Y93986D02*
X29121D01*
Y93917D01*
X29156D01*
Y93975D01*
X29144D01*
Y93986D01*
D02*
G37*
G36*
X28753Y93929D02*
X28741D01*
Y93917D01*
X28730D01*
Y93906D01*
X28718D01*
Y93894D01*
X28730D01*
Y93883D01*
X28741D01*
Y93894D01*
X28753D01*
Y93929D01*
D02*
G37*
G36*
X29121Y93917D02*
X29110D01*
Y93906D01*
Y93871D01*
X29121D01*
Y93917D01*
D02*
G37*
G36*
X27774Y93883D02*
X27762D01*
Y93871D01*
X27774D01*
Y93883D01*
D02*
G37*
G36*
X28741Y93871D02*
X28730D01*
Y93860D01*
X28741D01*
Y93871D01*
D02*
G37*
G36*
X28706Y93883D02*
X28695D01*
Y93860D01*
X28706D01*
Y93883D01*
D02*
G37*
G36*
X28787Y93963D02*
X28776D01*
Y93952D01*
X28764D01*
Y93906D01*
X28776D01*
Y93894D01*
X28787D01*
Y93837D01*
X28799D01*
Y93917D01*
X28787D01*
Y93963D01*
D02*
G37*
G36*
X28764Y93848D02*
X28753D01*
Y93837D01*
X28764D01*
Y93848D01*
D02*
G37*
G36*
X29167Y93883D02*
X29133D01*
Y93860D01*
Y93848D01*
X29144D01*
Y93825D01*
X29167D01*
Y93837D01*
X29179D01*
Y93860D01*
X29167D01*
Y93883D01*
D02*
G37*
G36*
X29133Y93825D02*
X29121D01*
Y93814D01*
X29133D01*
Y93825D01*
D02*
G37*
G36*
X27843Y93791D02*
X27820D01*
Y93779D01*
X27843D01*
Y93791D01*
D02*
G37*
G36*
X27808Y93802D02*
X27797D01*
Y93791D01*
Y93779D01*
X27808D01*
Y93802D01*
D02*
G37*
G36*
X28718Y93779D02*
X28706D01*
Y93768D01*
X28718D01*
Y93779D01*
D02*
G37*
G36*
Y93745D02*
X28706D01*
Y93733D01*
X28718D01*
Y93745D01*
D02*
G37*
G36*
X29179Y93814D02*
X29167D01*
Y93802D01*
X29156D01*
Y93768D01*
X29167D01*
Y93756D01*
X29179D01*
Y93722D01*
X29202D01*
Y93779D01*
X29190D01*
Y93791D01*
X29179D01*
Y93814D01*
D02*
G37*
G36*
X29167Y93745D02*
X29144D01*
Y93733D01*
X29156D01*
Y93722D01*
X29167D01*
Y93745D01*
D02*
G37*
G36*
X29593Y93699D02*
X29582D01*
Y93687D01*
X29593D01*
Y93699D01*
D02*
G37*
G36*
X28741D02*
X28730D01*
Y93687D01*
X28741D01*
Y93699D01*
D02*
G37*
G36*
X28764Y93676D02*
X28753D01*
Y93664D01*
X28764D01*
Y93676D01*
D02*
G37*
G36*
X27808Y93652D02*
X27797D01*
Y93641D01*
X27808D01*
Y93652D01*
D02*
G37*
G36*
X28753Y93641D02*
X28741D01*
Y93629D01*
X28753D01*
Y93641D01*
D02*
G37*
G36*
X29225Y93722D02*
X29213D01*
Y93710D01*
X29202D01*
Y93687D01*
X29190D01*
Y93652D01*
X29179D01*
Y93641D01*
Y93618D01*
X29202D01*
Y93664D01*
X29225D01*
Y93722D01*
D02*
G37*
G36*
X29444Y93606D02*
X29432D01*
Y93595D01*
X29444D01*
Y93606D01*
D02*
G37*
G36*
X29317Y93595D02*
X29271D01*
Y93583D01*
X29317D01*
Y93595D01*
D02*
G37*
G36*
X29236Y93629D02*
X29225D01*
Y93618D01*
X29213D01*
Y93583D01*
X29225D01*
Y93595D01*
X29236D01*
Y93629D01*
D02*
G37*
G36*
X27635Y93583D02*
X27624D01*
Y93560D01*
X27635D01*
Y93572D01*
Y93583D01*
D02*
G37*
G36*
X29213Y93572D02*
X29202D01*
Y93549D01*
X29213D01*
Y93560D01*
Y93572D01*
D02*
G37*
G36*
X29259Y93514D02*
X29248D01*
Y93503D01*
X29259D01*
Y93514D01*
D02*
G37*
G36*
X27774D02*
X27762D01*
Y93503D01*
X27774D01*
Y93514D01*
D02*
G37*
G36*
X27624Y93526D02*
X27612D01*
Y93503D01*
X27624D01*
Y93514D01*
Y93526D01*
D02*
G37*
G36*
X29213Y93514D02*
X29202D01*
Y93480D01*
X29213D01*
Y93503D01*
Y93514D01*
D02*
G37*
G36*
X27635Y93457D02*
X27624D01*
Y93445D01*
X27635D01*
Y93457D01*
D02*
G37*
G36*
X29259Y93445D02*
X29248D01*
Y93434D01*
X29259D01*
Y93445D01*
D02*
G37*
G36*
X29213Y93411D02*
X29202D01*
Y93399D01*
X29213D01*
Y93411D01*
D02*
G37*
G36*
X27797D02*
X27762D01*
Y93399D01*
X27797D01*
Y93411D01*
D02*
G37*
G36*
X30538Y93365D02*
X30526D01*
Y93353D01*
X30538D01*
Y93365D01*
D02*
G37*
G36*
X26921D02*
X26910D01*
Y93353D01*
X26921D01*
Y93365D01*
D02*
G37*
G36*
X27659Y93549D02*
X27647D01*
Y93537D01*
X27635D01*
Y93514D01*
X27647D01*
Y93491D01*
X27635D01*
Y93480D01*
X27647D01*
Y93468D01*
X27659D01*
Y93388D01*
X27647D01*
Y93353D01*
X27670D01*
Y93330D01*
X27693D01*
Y93468D01*
X27681D01*
Y93480D01*
X27659D01*
Y93491D01*
Y93503D01*
Y93549D01*
D02*
G37*
G36*
X29041Y93341D02*
X29029D01*
Y93318D01*
X29041D01*
Y93330D01*
Y93341D01*
D02*
G37*
G36*
X27624Y93353D02*
X27601D01*
Y93341D01*
X27589D01*
Y93330D01*
X27601D01*
Y93318D01*
X27612D01*
Y93330D01*
X27624D01*
Y93353D01*
D02*
G37*
G36*
X27728Y93318D02*
X27716D01*
Y93307D01*
X27728D01*
Y93318D01*
D02*
G37*
G36*
X30538Y93307D02*
X30503D01*
Y93249D01*
X30492D01*
Y93226D01*
Y93215D01*
Y93192D01*
X30480D01*
Y93157D01*
X30492D01*
Y93088D01*
X30503D01*
Y93100D01*
X30515D01*
Y93157D01*
X30526D01*
Y93169D01*
X30515D01*
Y93192D01*
X30526D01*
Y93203D01*
X30538D01*
Y93226D01*
X30526D01*
Y93261D01*
X30538D01*
Y93249D01*
X30561D01*
Y93272D01*
X30549D01*
Y93284D01*
X30538D01*
Y93307D01*
D02*
G37*
G36*
X27797Y93226D02*
X27774D01*
Y93215D01*
Y93203D01*
X27797D01*
Y93226D01*
D02*
G37*
G36*
X27751Y93169D02*
X27728D01*
Y93157D01*
Y93146D01*
X27751D01*
Y93169D01*
D02*
G37*
G36*
X27797Y93365D02*
X27774D01*
Y93341D01*
X27785D01*
Y93330D01*
X27797D01*
Y93318D01*
Y93261D01*
X27808D01*
Y93192D01*
X27797D01*
Y93077D01*
X27808D01*
Y93065D01*
X27820D01*
Y93077D01*
X27808D01*
Y93146D01*
X27820D01*
Y93100D01*
X27831D01*
Y93088D01*
X27854D01*
Y93111D01*
X27843D01*
Y93203D01*
X27831D01*
Y93261D01*
X27820D01*
Y93284D01*
X27808D01*
Y93341D01*
X27797D01*
Y93365D01*
D02*
G37*
G36*
X27739Y93134D02*
X27716D01*
Y93100D01*
X27705D01*
Y93077D01*
X27716D01*
Y93088D01*
X27739D01*
Y93100D01*
X27751D01*
Y93123D01*
X27739D01*
Y93134D01*
D02*
G37*
G36*
X28223Y93088D02*
X28200D01*
Y93065D01*
X28223D01*
Y93077D01*
Y93088D01*
D02*
G37*
G36*
X27647Y93318D02*
X27624D01*
Y93284D01*
X27612D01*
Y93226D01*
X27624D01*
Y93146D01*
X27635D01*
Y93088D01*
X27647D01*
Y93077D01*
X27659D01*
Y93065D01*
X27670D01*
Y93123D01*
X27659D01*
Y93146D01*
X27670D01*
Y93157D01*
X27716D01*
Y93192D01*
X27739D01*
Y93203D01*
X27751D01*
Y93226D01*
X27739D01*
Y93249D01*
Y93261D01*
X27716D01*
Y93284D01*
X27705D01*
Y93295D01*
X27693D01*
Y93284D01*
X27681D01*
Y93272D01*
X27670D01*
Y93261D01*
X27716D01*
Y93203D01*
X27705D01*
Y93192D01*
X27693D01*
Y93203D01*
X27670D01*
Y93180D01*
X27659D01*
Y93261D01*
X27647D01*
Y93318D01*
D02*
G37*
G36*
X27635Y93065D02*
X27624D01*
Y93054D01*
X27635D01*
Y93065D01*
D02*
G37*
G36*
X27831Y93042D02*
X27808D01*
Y93031D01*
Y93019D01*
X27831D01*
Y93042D01*
D02*
G37*
G36*
X27681D02*
X27670D01*
Y93031D01*
X27659D01*
Y93007D01*
X27670D01*
Y92996D01*
X27681D01*
Y93031D01*
Y93042D01*
D02*
G37*
G36*
X27866Y92996D02*
X27854D01*
Y92984D01*
X27866D01*
Y92996D01*
D02*
G37*
G36*
X27797Y92973D02*
X27785D01*
Y92962D01*
X27797D01*
Y92973D01*
D02*
G37*
G36*
X27705D02*
X27693D01*
Y92962D01*
X27705D01*
Y92973D01*
D02*
G37*
G36*
X29524Y92950D02*
X29501D01*
Y92927D01*
X29513D01*
Y92938D01*
X29524D01*
Y92950D01*
D02*
G37*
G36*
X27843Y92984D02*
X27820D01*
Y92927D01*
X27843D01*
Y92984D01*
D02*
G37*
G36*
X27797Y92938D02*
X27785D01*
Y92927D01*
X27797D01*
Y92938D01*
D02*
G37*
G36*
X27762Y92927D02*
X27751D01*
Y92915D01*
X27762D01*
Y92927D01*
D02*
G37*
G36*
X27659D02*
X27647D01*
Y92915D01*
X27659D01*
Y92927D01*
D02*
G37*
G36*
X27866Y92904D02*
X27854D01*
Y92892D01*
X27866D01*
Y92904D01*
D02*
G37*
G36*
X27705D02*
X27693D01*
Y92892D01*
X27705D01*
Y92904D01*
D02*
G37*
G36*
X27854Y92892D02*
X27843D01*
Y92881D01*
X27854D01*
Y92892D01*
D02*
G37*
G36*
X27659Y92881D02*
X27647D01*
Y92869D01*
X27659D01*
Y92881D01*
D02*
G37*
G36*
X27808Y92892D02*
X27797D01*
Y92881D01*
Y92846D01*
X27808D01*
Y92892D01*
D02*
G37*
G36*
X29467Y92846D02*
X29455D01*
Y92835D01*
X29467D01*
Y92846D01*
D02*
G37*
G36*
X29444D02*
X29432D01*
Y92835D01*
X29444D01*
Y92846D01*
D02*
G37*
G36*
X27716Y92858D02*
X27705D01*
Y92846D01*
Y92835D01*
X27716D01*
Y92858D01*
D02*
G37*
G36*
X27866Y92835D02*
X27843D01*
Y92812D01*
X27854D01*
Y92789D01*
X27877D01*
Y92800D01*
X27889D01*
Y92823D01*
X27866D01*
Y92835D01*
D02*
G37*
G36*
X27705Y92823D02*
X27693D01*
Y92812D01*
X27681D01*
Y92800D01*
X27693D01*
Y92789D01*
X27705D01*
Y92823D01*
D02*
G37*
G36*
X27762Y92881D02*
X27751D01*
Y92777D01*
X27762D01*
Y92789D01*
Y92800D01*
Y92881D01*
D02*
G37*
G36*
X29628Y92984D02*
X29593D01*
Y92962D01*
X29582D01*
Y92950D01*
X29570D01*
Y92938D01*
X29559D01*
Y92915D01*
X29547D01*
Y92892D01*
X29536D01*
Y92869D01*
X29513D01*
Y92858D01*
X29501D01*
Y92835D01*
X29513D01*
Y92800D01*
X29490D01*
Y92789D01*
X29455D01*
Y92766D01*
X29421D01*
Y92662D01*
X29432D01*
Y92616D01*
X29444D01*
Y92604D01*
X29455D01*
Y92581D01*
Y92570D01*
Y92535D01*
X29467D01*
Y92478D01*
X29478D01*
Y92466D01*
X29490D01*
Y92570D01*
X29501D01*
Y92581D01*
X29513D01*
Y92604D01*
X29524D01*
Y92628D01*
X29536D01*
Y92651D01*
X29524D01*
Y92685D01*
X29547D01*
Y92697D01*
X29536D01*
Y92731D01*
X29524D01*
Y92754D01*
X29501D01*
Y92720D01*
X29490D01*
Y92731D01*
Y92789D01*
X29513D01*
Y92777D01*
X29524D01*
Y92766D01*
X29536D01*
Y92731D01*
X29547D01*
Y92789D01*
X29559D01*
Y92800D01*
X29570D01*
Y92835D01*
X29582D01*
Y92892D01*
X29593D01*
Y92915D01*
X29605D01*
Y92950D01*
X29616D01*
Y92962D01*
X29628D01*
Y92984D01*
D02*
G37*
G36*
X27716Y92743D02*
X27705D01*
Y92720D01*
X27716D01*
Y92743D01*
D02*
G37*
G36*
X28280Y92731D02*
X28269D01*
Y92708D01*
X28280D01*
Y92731D01*
D02*
G37*
G36*
X27854Y92708D02*
X27843D01*
Y92697D01*
X27854D01*
Y92708D01*
D02*
G37*
G36*
X27774Y92754D02*
X27762D01*
Y92697D01*
X27774D01*
Y92708D01*
X27785D01*
Y92743D01*
X27774D01*
Y92754D01*
D02*
G37*
G36*
X27751Y92708D02*
X27728D01*
Y92697D01*
X27716D01*
Y92685D01*
Y92674D01*
X27739D01*
Y92697D01*
X27751D01*
Y92708D01*
D02*
G37*
G36*
X29697Y92685D02*
X29685D01*
Y92662D01*
X29697D01*
Y92674D01*
Y92685D01*
D02*
G37*
G36*
X27014Y92697D02*
X27002D01*
Y92651D01*
X27014D01*
Y92662D01*
X27025D01*
Y92674D01*
Y92685D01*
X27014D01*
Y92697D01*
D02*
G37*
G36*
X27820Y92651D02*
X27808D01*
Y92628D01*
X27831D01*
Y92639D01*
X27820D01*
Y92651D01*
D02*
G37*
G36*
X27774Y92639D02*
X27762D01*
Y92628D01*
X27774D01*
Y92639D01*
D02*
G37*
G36*
X29397Y92662D02*
X29375D01*
Y92628D01*
X29386D01*
Y92616D01*
X29397D01*
Y92662D01*
D02*
G37*
G36*
X29685Y92616D02*
X29674D01*
Y92604D01*
X29685D01*
Y92616D01*
D02*
G37*
G36*
X29397Y92604D02*
X29386D01*
Y92593D01*
X29397D01*
Y92604D01*
D02*
G37*
G36*
X29421Y92593D02*
X29409D01*
Y92581D01*
X29421D01*
Y92593D01*
D02*
G37*
G36*
X27797Y92604D02*
X27785D01*
Y92593D01*
X27774D01*
Y92581D01*
X27797D01*
Y92593D01*
Y92604D01*
D02*
G37*
G36*
X27728Y92639D02*
X27716D01*
Y92604D01*
X27728D01*
Y92581D01*
X27751D01*
Y92604D01*
X27739D01*
Y92628D01*
X27728D01*
Y92639D01*
D02*
G37*
G36*
X27048D02*
X27037D01*
Y92581D01*
X27014D01*
Y92604D01*
X27002D01*
Y92547D01*
X27014D01*
Y92558D01*
X27048D01*
Y92628D01*
Y92639D01*
D02*
G37*
G36*
X27900Y92570D02*
X27889D01*
Y92558D01*
X27900D01*
Y92570D01*
D02*
G37*
G36*
X27705Y92616D02*
X27693D01*
Y92604D01*
X27705D01*
Y92558D01*
X27716D01*
Y92581D01*
Y92593D01*
Y92604D01*
X27705D01*
Y92616D01*
D02*
G37*
G36*
X29651Y92558D02*
X29639D01*
Y92547D01*
X29651D01*
Y92558D01*
D02*
G37*
G36*
X27670Y92547D02*
X27659D01*
Y92535D01*
X27670D01*
Y92547D01*
D02*
G37*
G36*
X29409Y92524D02*
X29397D01*
Y92512D01*
X29409D01*
Y92524D01*
D02*
G37*
G36*
X27866D02*
X27854D01*
Y92512D01*
X27866D01*
Y92524D01*
D02*
G37*
G36*
X26956Y92547D02*
X26945D01*
Y92535D01*
Y92512D01*
X26956D01*
Y92547D01*
D02*
G37*
G36*
X29444Y92524D02*
X29421D01*
Y92501D01*
X29444D01*
Y92524D01*
D02*
G37*
G36*
X29397Y92512D02*
X29386D01*
Y92501D01*
X29397D01*
Y92512D01*
D02*
G37*
G36*
X27048Y92535D02*
X27037D01*
Y92512D01*
X27025D01*
Y92501D01*
X27014D01*
Y92512D01*
X27002D01*
Y92501D01*
X27014D01*
Y92455D01*
X27037D01*
Y92478D01*
X27048D01*
Y92489D01*
X27060D01*
Y92524D01*
X27048D01*
Y92535D01*
D02*
G37*
G36*
X27820Y92604D02*
X27808D01*
Y92547D01*
X27797D01*
Y92489D01*
X27820D01*
Y92501D01*
X27831D01*
Y92524D01*
Y92535D01*
Y92593D01*
X27820D01*
Y92604D01*
D02*
G37*
G36*
X29651Y92512D02*
X29639D01*
Y92501D01*
X29628D01*
Y92443D01*
X29616D01*
Y92420D01*
X29639D01*
Y92432D01*
X29651D01*
Y92455D01*
X29639D01*
Y92478D01*
X29651D01*
Y92512D01*
D02*
G37*
G36*
X27843Y92478D02*
X27820D01*
Y92466D01*
X27808D01*
Y92420D01*
X27820D01*
Y92432D01*
X27831D01*
Y92443D01*
X27843D01*
Y92478D01*
D02*
G37*
G36*
X27106Y92409D02*
X27094D01*
Y92397D01*
X27106D01*
Y92409D01*
D02*
G37*
G36*
X27071Y92455D02*
X27060D01*
Y92443D01*
X27048D01*
Y92409D01*
X27037D01*
Y92397D01*
X27025D01*
Y92386D01*
X27037D01*
Y92374D01*
X27048D01*
Y92386D01*
X27060D01*
Y92409D01*
X27071D01*
Y92432D01*
X27083D01*
Y92443D01*
X27071D01*
Y92455D01*
D02*
G37*
G36*
X27774Y92363D02*
X27762D01*
Y92351D01*
X27774D01*
Y92363D01*
D02*
G37*
G36*
X27854D02*
X27831D01*
Y92351D01*
X27820D01*
Y92340D01*
X27831D01*
Y92328D01*
X27854D01*
Y92340D01*
Y92351D01*
Y92363D01*
D02*
G37*
G36*
X27094Y92351D02*
X27071D01*
Y92340D01*
X27060D01*
Y92328D01*
X27094D01*
Y92351D01*
D02*
G37*
G36*
X29351Y92328D02*
X29340D01*
Y92317D01*
X29351D01*
Y92328D01*
D02*
G37*
G36*
X27014Y92340D02*
X27002D01*
Y92317D01*
X27014D01*
Y92340D01*
D02*
G37*
G36*
X26967Y92443D02*
X26945D01*
Y92420D01*
X26956D01*
Y92397D01*
Y92386D01*
Y92317D01*
X26979D01*
Y92340D01*
X26991D01*
Y92386D01*
X26979D01*
Y92409D01*
X26967D01*
Y92443D01*
D02*
G37*
G36*
X29651Y92328D02*
X29639D01*
Y92317D01*
X29651Y92305D01*
X29662D01*
Y92317D01*
X29651D01*
Y92328D01*
D02*
G37*
G36*
X29559Y92282D02*
X29547D01*
Y92270D01*
X29559D01*
Y92282D01*
D02*
G37*
G36*
X28280D02*
X28269D01*
Y92270D01*
X28280D01*
Y92282D01*
D02*
G37*
G36*
X27037Y92270D02*
X27014D01*
Y92259D01*
X27037D01*
Y92270D01*
D02*
G37*
G36*
X29639Y92409D02*
X29605D01*
Y92340D01*
X29593D01*
Y92294D01*
X29582D01*
Y92236D01*
X29616D01*
Y92270D01*
X29605D01*
Y92305D01*
X29616D01*
Y92317D01*
X29628D01*
Y92374D01*
X29639D01*
Y92409D01*
D02*
G37*
G36*
X27002Y92317D02*
X26991D01*
Y92305D01*
X26979D01*
Y92259D01*
X26991D01*
Y92236D01*
X27002D01*
Y92282D01*
X27014D01*
Y92305D01*
X27002D01*
Y92317D01*
D02*
G37*
G36*
X27866Y92305D02*
X27843D01*
Y92282D01*
X27854D01*
Y92270D01*
X27843D01*
Y92247D01*
Y92236D01*
Y92224D01*
X27866D01*
Y92236D01*
X27877D01*
Y92282D01*
X27866D01*
Y92305D01*
D02*
G37*
G36*
X29651Y92236D02*
X29639D01*
Y92190D01*
X29651D01*
Y92224D01*
Y92236D01*
D02*
G37*
G36*
X28200Y92201D02*
X28188D01*
Y92190D01*
X28200D01*
Y92201D01*
D02*
G37*
G36*
X30250Y92190D02*
X30238D01*
Y92178D01*
X30250D01*
Y92190D01*
D02*
G37*
G36*
X27094Y92317D02*
X27060D01*
Y92305D01*
X27048D01*
Y92282D01*
X27060D01*
Y92294D01*
X27071D01*
Y92259D01*
X27083D01*
Y92224D01*
X27071D01*
Y92213D01*
X27083D01*
Y92201D01*
X27094D01*
Y92178D01*
X27106D01*
Y92213D01*
Y92224D01*
Y92270D01*
X27094D01*
Y92317D01*
D02*
G37*
G36*
X29582Y92213D02*
X29570D01*
Y92201D01*
X29559D01*
Y92178D01*
X29547D01*
Y92144D01*
X29559D01*
Y92121D01*
X29570D01*
Y92098D01*
X29559D01*
Y92063D01*
X29570D01*
Y92052D01*
X29593D01*
Y92075D01*
X29582D01*
Y92086D01*
X29593D01*
Y92132D01*
X29582D01*
Y92144D01*
Y92155D01*
Y92178D01*
X29593D01*
Y92167D01*
X29605D01*
Y92178D01*
X29593D01*
Y92201D01*
X29582D01*
Y92213D01*
D02*
G37*
G36*
X27889Y92190D02*
X27854D01*
Y92178D01*
X27866D01*
Y92167D01*
X27889D01*
Y92190D01*
D02*
G37*
G36*
X27048Y92178D02*
X27037D01*
Y92167D01*
X27048D01*
Y92178D01*
D02*
G37*
G36*
X27071D02*
X27060D01*
Y92167D01*
Y92155D01*
X27083D01*
Y92167D01*
X27071D01*
Y92178D01*
D02*
G37*
G36*
X27014Y92167D02*
X27002D01*
Y92155D01*
X27014D01*
Y92167D01*
D02*
G37*
G36*
X27866Y92144D02*
X27854D01*
Y92132D01*
X27866D01*
Y92144D01*
D02*
G37*
G36*
X29363Y92121D02*
X29351D01*
Y92098D01*
X29363D01*
Y92109D01*
Y92121D01*
D02*
G37*
G36*
X27981Y92098D02*
X27969D01*
Y92086D01*
X27981D01*
Y92098D01*
D02*
G37*
G36*
X27889Y92086D02*
X27877D01*
Y92075D01*
X27889D01*
Y92086D01*
D02*
G37*
G36*
X27060D02*
X27048D01*
Y92075D01*
X27060D01*
Y92086D01*
D02*
G37*
G36*
X27117Y92167D02*
X27094D01*
Y92132D01*
X27106D01*
Y92063D01*
X27094D01*
Y92121D01*
X27083D01*
Y92098D01*
X27071D01*
Y92075D01*
X27083D01*
Y92063D01*
X27071D01*
Y92052D01*
X27083D01*
Y92040D01*
X27094D01*
Y91948D01*
X27106D01*
Y91879D01*
X27129D01*
Y91948D01*
X27117D01*
Y91960D01*
X27106D01*
Y92017D01*
X27117D01*
Y91994D01*
X27129D01*
Y91971D01*
X27140D01*
Y91867D01*
X27152D01*
Y91856D01*
X27163D01*
Y91867D01*
X27175D01*
Y91902D01*
X27163D01*
Y91913D01*
X27152D01*
Y91983D01*
X27140D01*
Y92075D01*
X27129D01*
Y92132D01*
Y92144D01*
Y92155D01*
X27117D01*
Y92167D01*
D02*
G37*
G36*
X29305Y92144D02*
X29282D01*
Y92132D01*
Y92121D01*
Y92075D01*
X29294D01*
Y92052D01*
X29305D01*
Y92144D01*
D02*
G37*
G36*
X29375Y91994D02*
X29363D01*
Y91983D01*
X29375D01*
Y91994D01*
D02*
G37*
G36*
X27048D02*
X27037D01*
Y91983D01*
X27048D01*
Y91994D01*
D02*
G37*
G36*
X27912Y91983D02*
X27900D01*
Y91971D01*
X27912D01*
Y91983D01*
D02*
G37*
G36*
X27083Y91994D02*
X27060D01*
Y91971D01*
X27083D01*
Y91994D01*
D02*
G37*
G36*
X29340Y91948D02*
X29317D01*
Y91936D01*
Y91925D01*
X29340D01*
Y91948D01*
D02*
G37*
G36*
X27094Y91902D02*
X27083D01*
Y91890D01*
X27094D01*
Y91902D01*
D02*
G37*
G36*
X29328D02*
X29317D01*
Y91879D01*
X29340D01*
Y91890D01*
X29328D01*
Y91902D01*
D02*
G37*
G36*
X28799Y91867D02*
X28787D01*
Y91856D01*
X28799D01*
Y91867D01*
D02*
G37*
G36*
X28810Y91810D02*
X28799D01*
Y91798D01*
X28810D01*
Y91810D01*
D02*
G37*
G36*
X28142D02*
X28131D01*
Y91798D01*
X28142D01*
Y91810D01*
D02*
G37*
G36*
X30123Y91798D02*
X30112D01*
Y91787D01*
X30123D01*
Y91798D01*
D02*
G37*
G36*
X27175Y91821D02*
X27152D01*
Y91810D01*
Y91787D01*
X27163D01*
Y91775D01*
X27175D01*
Y91764D01*
X27186D01*
Y91798D01*
X27175D01*
Y91821D01*
D02*
G37*
G36*
X28833Y91775D02*
X28810D01*
Y91752D01*
X28833D01*
Y91775D01*
D02*
G37*
G36*
Y91729D02*
X28810D01*
Y91718D01*
X28822D01*
Y91706D01*
X28833D01*
Y91718D01*
Y91729D01*
D02*
G37*
G36*
X27060Y91913D02*
X27048D01*
Y91902D01*
Y91890D01*
Y91879D01*
X27060D01*
Y91844D01*
X27071D01*
Y91821D01*
X27060D01*
Y91764D01*
X27071D01*
Y91752D01*
X27060D01*
Y91683D01*
X27071D01*
Y91672D01*
X27117D01*
Y91683D01*
X27129D01*
Y91718D01*
X27117D01*
Y91729D01*
X27106D01*
Y91810D01*
X27094D01*
Y91867D01*
X27083D01*
Y91879D01*
X27060D01*
Y91913D01*
D02*
G37*
G36*
X28833Y91672D02*
X28822D01*
Y91660D01*
X28833D01*
Y91672D01*
D02*
G37*
G36*
X27140Y91856D02*
X27129D01*
Y91798D01*
X27117D01*
Y91775D01*
Y91764D01*
X27129D01*
Y91741D01*
X27140D01*
Y91660D01*
X27129D01*
Y91649D01*
X27094D01*
Y91591D01*
X27106D01*
Y91602D01*
X27129D01*
Y91580D01*
X27140D01*
Y91510D01*
X27129D01*
Y91533D01*
X27106D01*
Y91499D01*
X27117D01*
Y91476D01*
X27129D01*
Y91464D01*
X27117D01*
Y91430D01*
X27129D01*
Y91407D01*
X27140D01*
Y91338D01*
X27152D01*
Y91384D01*
X27163D01*
Y91372D01*
X27186D01*
Y91384D01*
X27198D01*
Y91407D01*
X27209D01*
Y91418D01*
X27232D01*
Y91441D01*
X27221D01*
Y91499D01*
X27209D01*
Y91510D01*
X27198D01*
Y91522D01*
X27186D01*
Y91568D01*
X27175D01*
Y91614D01*
X27186D01*
Y91649D01*
X27175D01*
Y91672D01*
X27186D01*
Y91660D01*
X27198D01*
Y91706D01*
X27186D01*
Y91729D01*
X27163D01*
Y91683D01*
X27152D01*
Y91764D01*
X27140D01*
Y91856D01*
D02*
G37*
G36*
X30112Y91764D02*
X30088D01*
Y91741D01*
X30077D01*
Y91660D01*
X30065D01*
Y91625D01*
X30077D01*
Y91637D01*
X30088D01*
Y91660D01*
X30100D01*
Y91706D01*
Y91718D01*
X30112D01*
Y91764D01*
D02*
G37*
G36*
X27209Y91614D02*
X27198D01*
Y91602D01*
X27186D01*
Y91580D01*
X27198D01*
Y91591D01*
X27209D01*
Y91614D01*
D02*
G37*
G36*
X27232Y91568D02*
X27221D01*
Y91556D01*
X27209D01*
Y91545D01*
X27232D01*
Y91568D01*
D02*
G37*
G36*
X27255Y91556D02*
X27244D01*
Y91510D01*
X27267D01*
Y91545D01*
X27255D01*
Y91556D01*
D02*
G37*
G36*
X28499Y91487D02*
X28488D01*
Y91476D01*
X28499D01*
Y91487D01*
D02*
G37*
G36*
X30008Y91430D02*
X29996D01*
Y91418D01*
X30008D01*
Y91430D01*
D02*
G37*
G36*
X28511Y91464D02*
X28465D01*
Y91418D01*
X28430D01*
Y91430D01*
X28419D01*
Y91418D01*
X28430D01*
Y91395D01*
X28419D01*
Y91372D01*
X28407D01*
Y91361D01*
X28396D01*
Y91349D01*
X28384D01*
Y91326D01*
X28361D01*
Y91303D01*
X28350D01*
Y91292D01*
X28338D01*
Y91257D01*
X28326D01*
Y91246D01*
X28315D01*
Y91234D01*
X28303D01*
Y91246D01*
X28280D01*
Y91234D01*
X28269D01*
Y91211D01*
X28257D01*
Y91199D01*
X28246D01*
Y91188D01*
X28234D01*
Y91176D01*
X28223D01*
Y91165D01*
X28211D01*
Y91153D01*
X28200D01*
Y91142D01*
X28188D01*
Y91119D01*
X28177D01*
Y91107D01*
X28165D01*
Y91096D01*
X28177D01*
Y91084D01*
X28142D01*
Y91050D01*
X28131D01*
Y91038D01*
X28119D01*
Y91027D01*
X28108D01*
Y91015D01*
X28096D01*
Y90946D01*
X28108D01*
Y90923D01*
X28119D01*
Y90889D01*
X28108D01*
Y90877D01*
X28119D01*
Y90854D01*
X28131D01*
Y90842D01*
X28119D01*
Y90819D01*
X28131D01*
Y90739D01*
X28119D01*
Y90693D01*
X28165D01*
Y90704D01*
X28177D01*
Y90716D01*
X28234D01*
Y90727D01*
X28326D01*
Y90716D01*
X28280D01*
Y90704D01*
X28257D01*
Y90693D01*
X28246D01*
Y90681D01*
X28188D01*
Y90670D01*
X28177D01*
Y90681D01*
X28154D01*
Y90670D01*
X28119D01*
Y90647D01*
X28131D01*
Y90624D01*
X28142D01*
Y90578D01*
X28154D01*
Y90566D01*
X28165D01*
Y90554D01*
X28154D01*
Y90451D01*
X28142D01*
Y90439D01*
X28154D01*
Y90416D01*
X28177D01*
Y90428D01*
Y90439D01*
X28165D01*
Y90451D01*
X28211D01*
Y90439D01*
X28223D01*
Y90451D01*
X28234D01*
Y90462D01*
X28257D01*
Y90451D01*
X28280D01*
Y90474D01*
X28257D01*
Y90485D01*
X28326D01*
Y90508D01*
X28338D01*
Y90520D01*
X28350D01*
Y90508D01*
X28361D01*
Y90497D01*
X28372D01*
Y90508D01*
X28384D01*
Y90520D01*
X28419D01*
Y90531D01*
X28430D01*
Y90520D01*
X28453D01*
Y90531D01*
X28603D01*
Y90543D01*
X28660D01*
Y90578D01*
X28649D01*
Y90670D01*
X28637D01*
Y90716D01*
X28626D01*
Y90727D01*
X28614D01*
Y90762D01*
X28603D01*
Y90819D01*
X28614D01*
Y90877D01*
X28626D01*
Y90900D01*
X28637D01*
Y90923D01*
X28626D01*
Y90935D01*
X28568D01*
Y90946D01*
X28580D01*
Y90958D01*
X28568D01*
Y90981D01*
X28591D01*
Y90969D01*
X28603D01*
Y91015D01*
X28568D01*
Y91027D01*
X28580D01*
Y91038D01*
X28591D01*
Y91050D01*
X28603D01*
Y91061D01*
X28591D01*
Y91073D01*
X28580D01*
Y91107D01*
X28568D01*
Y91096D01*
X28557D01*
Y91130D01*
X28568D01*
Y91142D01*
X28591D01*
Y91176D01*
X28568D01*
Y91199D01*
X28557D01*
Y91223D01*
X28545D01*
Y91234D01*
X28557D01*
Y91246D01*
X28534D01*
Y91280D01*
X28545D01*
Y91292D01*
X28534D01*
Y91326D01*
X28522D01*
Y91349D01*
X28534D01*
Y91361D01*
X28522D01*
Y91372D01*
X28499D01*
Y91384D01*
X28511D01*
Y91464D01*
D02*
G37*
G36*
X27301Y91338D02*
X27290D01*
Y91326D01*
X27301D01*
Y91338D01*
D02*
G37*
G36*
Y91280D02*
X27290D01*
Y91268D01*
Y91246D01*
X27313D01*
Y91268D01*
X27301D01*
Y91280D01*
D02*
G37*
G36*
X27325Y91234D02*
X27301D01*
Y91223D01*
X27325D01*
Y91234D01*
D02*
G37*
G36*
X27244Y91199D02*
X27232D01*
Y91188D01*
X27244D01*
Y91199D01*
D02*
G37*
G36*
X28603Y91188D02*
X28591D01*
Y91176D01*
X28603D01*
Y91188D01*
D02*
G37*
G36*
X32680Y91176D02*
X32657D01*
Y91153D01*
X32680D01*
Y91176D01*
D02*
G37*
G36*
X32530Y91130D02*
X32495D01*
Y91119D01*
X32472D01*
Y91130D01*
X32438D01*
Y91119D01*
X32415D01*
Y91107D01*
X32334D01*
Y91096D01*
X32323D01*
Y91084D01*
X32357D01*
Y91096D01*
X32426D01*
Y91084D01*
X32449D01*
Y91073D01*
X32484D01*
Y91084D01*
X32495D01*
Y91096D01*
X32541D01*
Y91119D01*
X32530D01*
Y91130D01*
D02*
G37*
G36*
X27175Y91153D02*
X27152D01*
Y91119D01*
X27175D01*
Y91153D01*
D02*
G37*
G36*
X27255Y91096D02*
X27244D01*
Y91084D01*
X27255D01*
Y91096D01*
D02*
G37*
G36*
X27048D02*
X27037D01*
Y91084D01*
X27048D01*
Y91096D01*
D02*
G37*
G36*
X27037Y91084D02*
X27025D01*
Y91073D01*
X27037D01*
Y91084D01*
D02*
G37*
G36*
X32277Y91107D02*
X32219D01*
Y91096D01*
X32196D01*
Y91073D01*
X32208D01*
Y91061D01*
X32242D01*
Y91073D01*
X32254D01*
Y91084D01*
X32311D01*
Y91096D01*
X32277D01*
Y91107D01*
D02*
G37*
G36*
X27025Y91073D02*
X27014D01*
Y91061D01*
X27025D01*
Y91073D01*
D02*
G37*
G36*
X27014Y91061D02*
X27002D01*
Y91050D01*
X27014D01*
Y91061D01*
D02*
G37*
G36*
X31655Y91050D02*
X31620D01*
Y91038D01*
X31655D01*
Y91050D01*
D02*
G37*
G36*
X31540D02*
X31471D01*
Y91038D01*
X31424D01*
Y91050D01*
X31252D01*
Y91038D01*
X31263D01*
Y91015D01*
X31240D01*
Y91004D01*
X31378D01*
Y90992D01*
X31413D01*
Y90981D01*
X31424D01*
Y90958D01*
X31401D01*
Y90969D01*
X31378D01*
Y90981D01*
X31355D01*
Y90992D01*
X31321D01*
Y90969D01*
X31309D01*
Y90958D01*
X31275D01*
Y90969D01*
X31298D01*
Y90992D01*
X31240D01*
Y90981D01*
X31217D01*
Y90969D01*
X31148D01*
Y90958D01*
X31137D01*
Y90969D01*
X31125D01*
Y90981D01*
X31113D01*
Y90969D01*
X31102D01*
Y90946D01*
X31079D01*
Y90958D01*
X30929D01*
Y90969D01*
X30918D01*
Y90981D01*
X30883D01*
Y90969D01*
X30849D01*
Y90981D01*
X30837D01*
Y90969D01*
X30825D01*
Y90981D01*
X30814D01*
Y90969D01*
X30756D01*
Y90981D01*
X30745D01*
Y90969D01*
X30733D01*
Y90958D01*
X30676D01*
Y90946D01*
X30699D01*
Y90935D01*
X30710D01*
Y90923D01*
X30952D01*
Y90912D01*
X30975D01*
Y90900D01*
X30998D01*
Y90912D01*
X30987D01*
Y90935D01*
X30998D01*
Y90923D01*
X31240D01*
Y90935D01*
X31252D01*
Y90946D01*
X31574D01*
Y90958D01*
X31632D01*
Y91004D01*
X31574D01*
Y90992D01*
X31563D01*
Y90981D01*
X31517D01*
Y90992D01*
X31505D01*
Y91004D01*
X31459D01*
Y91015D01*
X31482D01*
Y91027D01*
X31493D01*
Y91038D01*
X31505D01*
Y91027D01*
X31517D01*
Y91038D01*
X31540D01*
Y91050D01*
D02*
G37*
G36*
X28660D02*
X28649D01*
Y91038D01*
X28660D01*
Y91050D01*
D02*
G37*
G36*
X27002D02*
X26991D01*
Y91038D01*
X27002D01*
Y91050D01*
D02*
G37*
G36*
X31240D02*
X31183D01*
Y91038D01*
X31206D01*
Y91027D01*
X31229D01*
Y91038D01*
X31240D01*
Y91050D01*
D02*
G37*
G36*
X31758Y91038D02*
X31735D01*
Y91015D01*
X31758D01*
Y91027D01*
Y91038D01*
D02*
G37*
G36*
X31839Y91015D02*
X31793D01*
Y91004D01*
X31839D01*
Y91015D01*
D02*
G37*
G36*
X31183D02*
X31148D01*
Y91004D01*
X31183D01*
Y91015D01*
D02*
G37*
G36*
X30768D02*
X30756D01*
Y91004D01*
X30768D01*
Y91015D01*
D02*
G37*
G36*
X27060Y91050D02*
X27037D01*
Y91038D01*
X27025D01*
Y91027D01*
X27014D01*
Y91015D01*
X27002D01*
Y91004D01*
X26979D01*
Y91027D01*
X26991D01*
Y91038D01*
X26956D01*
Y91004D01*
X26945D01*
Y90992D01*
X26933D01*
Y90981D01*
X26921D01*
Y90946D01*
X26910D01*
Y90912D01*
X26898D01*
Y90900D01*
X26887D01*
Y90889D01*
X26875D01*
Y90877D01*
X26864D01*
Y90865D01*
X26852D01*
Y90854D01*
X26841D01*
Y90842D01*
X26829D01*
Y90831D01*
X26818D01*
Y90819D01*
X26806D01*
Y90808D01*
X26795D01*
Y90796D01*
X26783D01*
Y90785D01*
X26772D01*
Y90773D01*
X26760D01*
Y90750D01*
X26737D01*
Y90762D01*
X26726D01*
Y90739D01*
X26714D01*
Y90727D01*
X26691D01*
Y90704D01*
X26668D01*
Y90693D01*
X26656D01*
Y90681D01*
X26645D01*
Y90670D01*
X26634D01*
Y90658D01*
X26622D01*
Y90647D01*
X26610D01*
Y90635D01*
X26599D01*
Y90624D01*
X26576D01*
Y90578D01*
X26541D01*
Y90566D01*
X26530D01*
Y90531D01*
X26495D01*
Y90520D01*
X26484D01*
Y90531D01*
X26472D01*
Y90497D01*
X26461D01*
Y90485D01*
X26438D01*
Y90462D01*
X26426D01*
Y90451D01*
X26403D01*
Y90439D01*
X26392D01*
Y90428D01*
X26380D01*
Y90416D01*
X26369D01*
Y90405D01*
X26357D01*
Y90393D01*
X26346D01*
Y90382D01*
X26334D01*
Y90370D01*
X26323D01*
Y90359D01*
X26311D01*
Y90347D01*
X26300D01*
Y90336D01*
X26288D01*
Y90324D01*
X26276D01*
Y90347D01*
X26254D01*
Y90336D01*
X26242D01*
Y90324D01*
X26230D01*
Y90313D01*
X26219D01*
Y90290D01*
X26207D01*
Y90301D01*
X26196D01*
Y90290D01*
X26184D01*
Y90267D01*
X26196D01*
Y90255D01*
X26207D01*
Y90244D01*
X26242D01*
Y90255D01*
X26254D01*
Y90267D01*
X26276D01*
Y90255D01*
X26288D01*
Y90267D01*
X26357D01*
Y90278D01*
X26369D01*
Y90290D01*
X26426D01*
Y90301D01*
X26449D01*
Y90290D01*
X26472D01*
Y90301D01*
X26484D01*
Y90313D01*
X26449D01*
Y90336D01*
X26484D01*
Y90359D01*
X26507D01*
Y90370D01*
X26518D01*
Y90405D01*
X26541D01*
Y90416D01*
X26553D01*
Y90428D01*
X26564D01*
Y90462D01*
X26576D01*
Y90474D01*
X26610D01*
Y90497D01*
X26634D01*
Y90508D01*
X26645D01*
Y90520D01*
X26656D01*
Y90531D01*
X26668D01*
Y90554D01*
X26680D01*
Y90566D01*
X26703D01*
Y90578D01*
X26714D01*
Y90589D01*
X26726D01*
Y90601D01*
X26749D01*
Y90612D01*
X26760D01*
Y90635D01*
X26772D01*
Y90647D01*
X26783D01*
Y90658D01*
X26795D01*
Y90670D01*
X26806D01*
Y90681D01*
X26818D01*
Y90693D01*
X26829D01*
Y90670D01*
X26818D01*
Y90658D01*
X26852D01*
Y90681D01*
X26864D01*
Y90670D01*
X26875D01*
Y90681D01*
X26887D01*
Y90704D01*
X26898D01*
Y90716D01*
X26910D01*
Y90727D01*
X26921D01*
Y90739D01*
X26933D01*
Y90750D01*
X26945D01*
Y90762D01*
X26956D01*
Y90773D01*
X26967D01*
Y90785D01*
X26979D01*
Y90796D01*
X26991D01*
Y90808D01*
X27002D01*
Y90819D01*
X27037D01*
Y90808D01*
X27048D01*
Y90819D01*
X27037D01*
Y90854D01*
X27060D01*
Y90842D01*
X27071D01*
Y90877D01*
X27083D01*
Y90935D01*
X27071D01*
Y90958D01*
X27060D01*
Y90981D01*
X27071D01*
Y90992D01*
X27060D01*
Y91050D01*
D02*
G37*
G36*
X32127Y91004D02*
X32092D01*
Y90992D01*
X32127D01*
Y91004D01*
D02*
G37*
G36*
X31712Y91015D02*
X31632D01*
Y91004D01*
X31655D01*
Y90992D01*
X31678D01*
Y91004D01*
X31712D01*
Y91015D01*
D02*
G37*
G36*
X31021Y91004D02*
X31010D01*
Y90992D01*
X31021D01*
Y91004D01*
D02*
G37*
G36*
X30733D02*
X30722D01*
Y90992D01*
X30733D01*
Y91004D01*
D02*
G37*
G36*
X28672D02*
X28660D01*
Y90992D01*
X28672D01*
Y91004D01*
D02*
G37*
G36*
X31897D02*
X31850D01*
Y90992D01*
X31897D01*
Y91004D01*
D02*
G37*
G36*
X32081Y90992D02*
X31943D01*
Y90969D01*
X32069D01*
Y90981D01*
X32081D01*
Y90992D01*
D02*
G37*
G36*
X31747D02*
X31689D01*
Y90969D01*
X31735D01*
Y90981D01*
X31747D01*
Y90992D01*
D02*
G37*
G36*
X29927D02*
X29881D01*
Y90981D01*
X29893D01*
Y90969D01*
X29927D01*
Y90992D01*
D02*
G37*
G36*
X31839D02*
X31793D01*
Y90969D01*
X31839D01*
Y90958D01*
X31908D01*
Y90981D01*
X31839D01*
Y90992D01*
D02*
G37*
G36*
X31747Y90958D02*
X31701D01*
Y90935D01*
X31712D01*
Y90923D01*
X31770D01*
Y90946D01*
X31747D01*
Y90958D01*
D02*
G37*
G36*
X31666Y90946D02*
X31620D01*
Y90935D01*
X31632D01*
Y90923D01*
X31666D01*
Y90946D01*
D02*
G37*
G36*
X30446D02*
X30422D01*
Y90923D01*
X30446D01*
Y90935D01*
Y90946D01*
D02*
G37*
G36*
X30849Y90912D02*
X30803D01*
Y90889D01*
X30825D01*
Y90877D01*
X30837D01*
Y90889D01*
X30849D01*
Y90912D01*
D02*
G37*
G36*
X30768Y90900D02*
X30687D01*
Y90889D01*
X30699D01*
Y90877D01*
X30756D01*
Y90889D01*
X30768D01*
Y90900D01*
D02*
G37*
G36*
X30653Y90889D02*
X30641D01*
Y90877D01*
X30653D01*
Y90889D01*
D02*
G37*
G36*
X31424D02*
X31413D01*
Y90865D01*
X31436D01*
Y90877D01*
X31424D01*
Y90889D01*
D02*
G37*
G36*
X30641Y90877D02*
X30630D01*
Y90865D01*
X30641D01*
Y90877D01*
D02*
G37*
G36*
X30572Y90865D02*
X30561D01*
Y90854D01*
X30572D01*
Y90865D01*
D02*
G37*
G36*
X30526D02*
X30515D01*
Y90854D01*
X30526D01*
Y90865D01*
D02*
G37*
G36*
X30307Y90842D02*
X30273D01*
Y90831D01*
X30261D01*
Y90819D01*
X30307D01*
Y90842D01*
D02*
G37*
G36*
X30112Y90819D02*
X30065D01*
Y90808D01*
X30112D01*
Y90819D01*
D02*
G37*
G36*
X26760D02*
X26726D01*
Y90808D01*
X26760D01*
Y90819D01*
D02*
G37*
G36*
X30215D02*
X30192D01*
Y90808D01*
X30181D01*
Y90796D01*
X30135D01*
Y90785D01*
X30123D01*
Y90773D01*
X30158D01*
Y90762D01*
X30169D01*
Y90773D01*
X30204D01*
Y90796D01*
X30227D01*
Y90785D01*
X30261D01*
Y90808D01*
X30215D01*
Y90819D01*
D02*
G37*
G36*
X30008Y90808D02*
X29973D01*
Y90796D01*
X29985D01*
Y90785D01*
X29996D01*
Y90796D01*
X30008D01*
Y90808D01*
D02*
G37*
G36*
X26726Y90785D02*
X26714D01*
Y90773D01*
X26726D01*
Y90785D01*
D02*
G37*
G36*
X30123Y90773D02*
X30065D01*
Y90762D01*
X30123D01*
Y90773D01*
D02*
G37*
G36*
X29916Y90808D02*
X29904D01*
Y90785D01*
X29916D01*
Y90773D01*
X29939D01*
Y90739D01*
X29950D01*
Y90727D01*
X29973D01*
Y90739D01*
X30042D01*
Y90750D01*
X30054D01*
Y90762D01*
X30042D01*
Y90773D01*
X30019D01*
Y90762D01*
X29962D01*
Y90773D01*
X29950D01*
Y90785D01*
X29939D01*
Y90796D01*
X29916D01*
Y90808D01*
D02*
G37*
G36*
X29927Y90750D02*
X29858D01*
Y90739D01*
X29847D01*
Y90727D01*
X29858D01*
Y90716D01*
X29904D01*
Y90727D01*
X29927D01*
Y90739D01*
Y90750D01*
D02*
G37*
G36*
X30342Y90716D02*
X30307D01*
Y90704D01*
X30319D01*
Y90693D01*
X30330D01*
Y90704D01*
X30342D01*
Y90716D01*
D02*
G37*
G36*
X30100Y90681D02*
X30019D01*
Y90670D01*
X30100D01*
Y90681D01*
D02*
G37*
G36*
X29881D02*
X29870D01*
Y90670D01*
X29881D01*
Y90681D01*
D02*
G37*
G36*
X26818Y90658D02*
X26806D01*
Y90635D01*
X26818D01*
Y90658D01*
D02*
G37*
G36*
X26495D02*
X26484D01*
Y90635D01*
X26495D01*
Y90658D01*
D02*
G37*
G36*
X29824Y90635D02*
X29812D01*
Y90624D01*
X29824D01*
Y90635D01*
D02*
G37*
G36*
X29973Y90624D02*
X29962D01*
Y90612D01*
X29973D01*
Y90624D01*
D02*
G37*
G36*
X26783D02*
X26772D01*
Y90612D01*
X26783D01*
Y90624D01*
D02*
G37*
G36*
X26495D02*
X26484D01*
Y90612D01*
X26495D01*
Y90624D01*
D02*
G37*
G36*
X30745D02*
X30722D01*
Y90612D01*
X30733D01*
Y90601D01*
X30745D01*
Y90612D01*
Y90624D01*
D02*
G37*
G36*
X31010Y90612D02*
X30952D01*
Y90589D01*
X31010D01*
Y90601D01*
Y90612D01*
D02*
G37*
G36*
X30906Y90601D02*
X30895D01*
Y90589D01*
X30906D01*
Y90601D01*
D02*
G37*
G36*
X30641D02*
X30630D01*
Y90589D01*
X30641D01*
Y90601D01*
D02*
G37*
G36*
X30353Y90612D02*
X30342D01*
Y90589D01*
X30353D01*
Y90612D01*
D02*
G37*
G36*
X31447Y90589D02*
X31436D01*
Y90578D01*
X31447D01*
Y90589D01*
D02*
G37*
G36*
X30849D02*
X30803D01*
Y90578D01*
X30849D01*
Y90589D01*
D02*
G37*
G36*
X30250D02*
X30215D01*
Y90578D01*
X30250D01*
Y90589D01*
D02*
G37*
G36*
X29881D02*
X29870D01*
Y90578D01*
X29881D01*
Y90589D01*
D02*
G37*
G36*
X28764D02*
X28753D01*
Y90578D01*
X28764D01*
Y90589D01*
D02*
G37*
G36*
X26956D02*
X26945D01*
Y90578D01*
X26956D01*
Y90589D01*
D02*
G37*
G36*
X26760D02*
X26749D01*
Y90578D01*
X26760D01*
Y90589D01*
D02*
G37*
G36*
X32564Y90578D02*
X32553D01*
Y90566D01*
X32564D01*
Y90578D01*
D02*
G37*
G36*
X30123Y90589D02*
X30077D01*
Y90578D01*
X30065D01*
Y90566D01*
X30100D01*
Y90578D01*
X30123D01*
Y90589D01*
D02*
G37*
G36*
X30019Y90578D02*
X30008D01*
Y90566D01*
X30019D01*
Y90578D01*
D02*
G37*
G36*
X29778D02*
X29766D01*
Y90566D01*
X29778D01*
Y90578D01*
D02*
G37*
G36*
X30296Y90566D02*
X30273D01*
Y90543D01*
X30296D01*
Y90566D01*
D02*
G37*
G36*
X28142D02*
X28131D01*
Y90543D01*
X28142D01*
Y90566D01*
D02*
G37*
G36*
X26426Y90601D02*
X26403D01*
Y90589D01*
X26392D01*
Y90578D01*
X26403D01*
X26415Y90589D01*
Y90554D01*
X26426D01*
Y90543D01*
X26438D01*
Y90589D01*
X26426D01*
Y90601D01*
D02*
G37*
G36*
X26403Y90566D02*
X26369D01*
Y90543D01*
X26403D01*
Y90566D01*
D02*
G37*
G36*
X32564Y90543D02*
X32553D01*
Y90531D01*
X32564D01*
Y90543D01*
D02*
G37*
G36*
X30480D02*
X30468D01*
Y90531D01*
X30480D01*
Y90543D01*
D02*
G37*
G36*
X30215D02*
X30204D01*
Y90531D01*
X30215D01*
Y90543D01*
D02*
G37*
G36*
X32530Y90531D02*
X32519D01*
Y90520D01*
X32530D01*
Y90531D01*
D02*
G37*
G36*
X28660D02*
X28649D01*
Y90520D01*
X28660D01*
Y90531D01*
D02*
G37*
G36*
X26449D02*
X26438D01*
Y90520D01*
X26449D01*
Y90531D01*
D02*
G37*
G36*
X30273Y90520D02*
X30250D01*
Y90508D01*
Y90497D01*
X30273D01*
Y90520D01*
D02*
G37*
G36*
X28568D02*
X28557D01*
Y90497D01*
X28568D01*
Y90485D01*
X28545D01*
Y90497D01*
X28511D01*
Y90474D01*
X28499D01*
Y90451D01*
X28522D01*
Y90462D01*
X28534D01*
Y90474D01*
X28557D01*
Y90462D01*
X28580D01*
Y90474D01*
X28591D01*
Y90485D01*
X28614D01*
Y90508D01*
X28568D01*
Y90520D01*
D02*
G37*
G36*
X26691Y90497D02*
X26668D01*
Y90485D01*
X26691D01*
Y90497D01*
D02*
G37*
G36*
X28419Y90485D02*
X28407D01*
Y90474D01*
X28419D01*
Y90485D01*
D02*
G37*
G36*
X28372D02*
X28350D01*
Y90474D01*
X28372D01*
Y90485D01*
D02*
G37*
G36*
X28488D02*
X28465D01*
Y90462D01*
X28488D01*
Y90485D01*
D02*
G37*
G36*
X26645D02*
X26634D01*
Y90451D01*
X26645D01*
Y90462D01*
X26656D01*
Y90474D01*
X26645D01*
Y90485D01*
D02*
G37*
G36*
X28568Y90451D02*
X28557D01*
Y90439D01*
X28568D01*
Y90451D01*
D02*
G37*
G36*
X28453D02*
X28442D01*
Y90439D01*
X28453D01*
Y90451D01*
D02*
G37*
G36*
X26634D02*
X26622D01*
Y90439D01*
X26634D01*
Y90451D01*
D02*
G37*
G36*
X28511Y90439D02*
X28499D01*
Y90428D01*
X28511D01*
Y90439D01*
D02*
G37*
G36*
X26622D02*
X26610D01*
Y90428D01*
X26622D01*
Y90439D01*
D02*
G37*
G36*
X26334Y90405D02*
X26311D01*
Y90393D01*
X26334D01*
Y90405D01*
D02*
G37*
G36*
X26311Y90393D02*
X26300D01*
Y90382D01*
X26311D01*
Y90393D01*
D02*
G37*
G36*
X26300Y90382D02*
X26288D01*
Y90370D01*
X26300D01*
Y90382D01*
D02*
G37*
G36*
X28234D02*
X28211D01*
Y90359D01*
X28234D01*
Y90370D01*
Y90382D01*
D02*
G37*
G36*
X28545Y90359D02*
X28534D01*
Y90347D01*
X28545D01*
Y90359D01*
D02*
G37*
G36*
X32426Y90313D02*
X32415D01*
Y90290D01*
X32426D01*
Y90313D01*
D02*
G37*
G36*
X27463Y90324D02*
X27440D01*
Y90313D01*
Y90301D01*
Y90290D01*
X27463D01*
Y90324D01*
D02*
G37*
G36*
X26161Y90255D02*
X26150D01*
Y90244D01*
X26161D01*
Y90255D01*
D02*
G37*
G36*
X28511Y90220D02*
X28499D01*
Y90209D01*
X28511D01*
Y90220D01*
D02*
G37*
G36*
X26346Y90209D02*
X26334D01*
Y90197D01*
X26346D01*
Y90209D01*
D02*
G37*
G36*
X32323Y90197D02*
X32311D01*
Y90186D01*
X32323D01*
Y90197D01*
D02*
G37*
G36*
X26311D02*
X26265D01*
Y90186D01*
X26276D01*
Y90175D01*
X26288D01*
Y90163D01*
X26311D01*
Y90175D01*
X26323D01*
Y90186D01*
X26311D01*
Y90197D01*
D02*
G37*
G36*
X32323Y90163D02*
X32311D01*
Y90151D01*
X32323D01*
Y90163D01*
D02*
G37*
G36*
X26254D02*
X26196D01*
Y90151D01*
X26254D01*
Y90163D01*
D02*
G37*
G36*
X27071Y90151D02*
X27060D01*
Y90140D01*
X27071D01*
Y90151D01*
D02*
G37*
G36*
X30687Y90128D02*
X30676D01*
Y90117D01*
X30687D01*
Y90128D01*
D02*
G37*
G36*
X28522Y90105D02*
X28499D01*
Y90094D01*
X28522D01*
Y90105D01*
D02*
G37*
G36*
X27198Y90128D02*
X27186D01*
Y90105D01*
X27175D01*
Y90094D01*
X27198D01*
Y90105D01*
Y90117D01*
Y90128D01*
D02*
G37*
G36*
X28465Y90094D02*
X28419D01*
Y90082D01*
Y90071D01*
X28465D01*
Y90094D01*
D02*
G37*
G36*
X27014Y90082D02*
X27002D01*
Y90071D01*
X27014D01*
Y90082D01*
D02*
G37*
G36*
X27198Y89967D02*
X27152D01*
Y89956D01*
X27198D01*
Y89967D01*
D02*
G37*
G36*
X27117Y89944D02*
X27094D01*
Y89933D01*
X27048D01*
Y89910D01*
X27071D01*
Y89921D01*
X27106D01*
Y89933D01*
X27117D01*
Y89944D01*
D02*
G37*
G36*
X27014Y89921D02*
X26991D01*
Y89910D01*
X27014D01*
Y89921D01*
D02*
G37*
G36*
X32184Y89886D02*
X32173D01*
Y89875D01*
X32184D01*
Y89886D01*
D02*
G37*
G36*
X26945D02*
X26921D01*
Y89875D01*
X26945D01*
Y89886D01*
D02*
G37*
G36*
X31424Y89875D02*
X31401D01*
Y89852D01*
X31413D01*
Y89841D01*
X31424D01*
Y89875D01*
D02*
G37*
G36*
X31367D02*
X31344D01*
Y89864D01*
X31332D01*
Y89852D01*
Y89841D01*
X31355D01*
Y89852D01*
X31367D01*
Y89875D01*
D02*
G37*
G36*
X31309Y89864D02*
X31263D01*
Y89841D01*
X31309D01*
Y89864D01*
D02*
G37*
G36*
X31206Y89852D02*
X31113D01*
Y89841D01*
X31102D01*
Y89829D01*
X31056D01*
Y89841D01*
X31044D01*
Y89852D01*
X31033D01*
Y89841D01*
X31021D01*
Y89829D01*
X30952D01*
Y89817D01*
X31021D01*
Y89829D01*
X31056D01*
Y89806D01*
X30952D01*
Y89817D01*
X30941D01*
Y89806D01*
X30906D01*
Y89794D01*
X30883D01*
Y89783D01*
X30756D01*
Y89794D01*
X30872D01*
Y89817D01*
X30756D01*
Y89806D01*
X30745D01*
Y89794D01*
X30733D01*
Y89806D01*
X30664D01*
Y89817D01*
X30618D01*
Y89794D01*
X30607D01*
Y89783D01*
X30584D01*
Y89771D01*
X30561D01*
Y89783D01*
X30526D01*
Y89794D01*
X30515D01*
Y89806D01*
X30503D01*
Y89794D01*
X30492D01*
Y89771D01*
X30515D01*
Y89760D01*
X30480D01*
Y89771D01*
X30468D01*
Y89783D01*
X30330D01*
Y89771D01*
X30307D01*
Y89783D01*
X30296D01*
Y89771D01*
X30181D01*
Y89737D01*
X30158D01*
Y89748D01*
X30146D01*
Y89760D01*
X30100D01*
Y89748D01*
X30088D01*
Y89760D01*
X30065D01*
Y89748D01*
X30054D01*
Y89645D01*
X30065D01*
Y89472D01*
X30042D01*
Y89495D01*
X30054D01*
Y89518D01*
X30042D01*
Y89530D01*
X30031D01*
Y89518D01*
X30019D01*
Y89483D01*
X30008D01*
Y89449D01*
X30019D01*
Y89391D01*
X30031D01*
Y89334D01*
X30042D01*
Y89322D01*
X30054D01*
Y89265D01*
X30065D01*
Y89161D01*
X30077D01*
Y89115D01*
X30088D01*
Y89103D01*
X30100D01*
Y89034D01*
X30112D01*
Y88965D01*
X30123D01*
Y88919D01*
X30112D01*
Y88885D01*
X30123D01*
Y88804D01*
X30135D01*
Y88781D01*
X30146D01*
Y88712D01*
X30158D01*
Y88654D01*
X30146D01*
Y88631D01*
X30158D01*
Y88620D01*
X30169D01*
Y88562D01*
X30158D01*
Y88551D01*
X30169D01*
Y88459D01*
X30181D01*
Y88447D01*
X30192D01*
Y88436D01*
X30204D01*
Y88424D01*
X30215D01*
Y88378D01*
X30204D01*
Y88412D01*
X30192D01*
Y88355D01*
X30204D01*
Y88274D01*
X30215D01*
Y88171D01*
X30227D01*
Y88159D01*
X30238D01*
Y88102D01*
X30250D01*
Y87998D01*
X30261D01*
Y87986D01*
X30250D01*
Y87975D01*
X30261D01*
Y87894D01*
X30273D01*
Y87871D01*
X30284D01*
Y87791D01*
X30296D01*
Y87664D01*
X30307D01*
Y87560D01*
X30330D01*
Y87583D01*
X30342D01*
Y87629D01*
X30353D01*
Y87664D01*
X30399D01*
Y87675D01*
X30388D01*
Y87687D01*
X30376D01*
Y87721D01*
X30388D01*
Y87710D01*
X30399D01*
Y87698D01*
X30422D01*
Y87721D01*
X30388D01*
Y87756D01*
X30399D01*
Y87791D01*
X30411D01*
Y87814D01*
X30422D01*
Y87837D01*
X30434D01*
Y87848D01*
X30422D01*
Y87871D01*
Y87883D01*
X30434D01*
Y87917D01*
X30457D01*
Y87940D01*
X30434D01*
Y87952D01*
X30446D01*
Y88009D01*
X30457D01*
Y88021D01*
X30468D01*
Y88044D01*
X30480D01*
Y88090D01*
X30492D01*
Y88136D01*
X30503D01*
Y88148D01*
X30515D01*
Y88171D01*
X30526D01*
Y88217D01*
X30538D01*
Y88228D01*
X30526D01*
Y88240D01*
X30549D01*
Y88263D01*
X30538D01*
Y88274D01*
X30549D01*
Y88286D01*
X30561D01*
Y88297D01*
X30584D01*
Y88274D01*
X30572D01*
Y88240D01*
X30630D01*
Y88263D01*
X30618D01*
Y88274D01*
X30653D01*
Y88263D01*
X30664D01*
Y88251D01*
X30653D01*
Y88240D01*
X30641D01*
Y88205D01*
X30630D01*
Y88136D01*
X30607D01*
Y88148D01*
X30595D01*
Y88159D01*
X30584D01*
Y88171D01*
X30572D01*
Y88125D01*
X30584D01*
Y88136D01*
X30595D01*
Y88125D01*
X30607D01*
Y88113D01*
X30618D01*
Y88102D01*
X30607D01*
Y88090D01*
X30584D01*
Y88078D01*
X30572D01*
Y88090D01*
X30561D01*
Y88078D01*
X30572D01*
Y88067D01*
X30549D01*
Y88055D01*
X30538D01*
Y88044D01*
X30526D01*
Y87998D01*
X30538D01*
Y87986D01*
X30515D01*
Y87963D01*
X30526D01*
Y87952D01*
X30538D01*
Y87940D01*
X30561D01*
Y87975D01*
X30572D01*
Y87986D01*
X30561D01*
Y87998D01*
X30584D01*
Y88009D01*
X30595D01*
Y88021D01*
X30607D01*
Y88067D01*
X30618D01*
Y88090D01*
X30630D01*
Y88125D01*
X30641D01*
Y88136D01*
X30653D01*
Y88159D01*
X30664D01*
Y88182D01*
X30676D01*
Y88205D01*
X30687D01*
Y88228D01*
X30699D01*
Y88251D01*
X30710D01*
Y88274D01*
X30722D01*
Y88297D01*
X30733D01*
Y88309D01*
X30745D01*
Y88320D01*
X30756D01*
Y88355D01*
X30768D01*
Y88378D01*
X30779D01*
Y88401D01*
X30768D01*
Y88412D01*
X30779D01*
Y88424D01*
X30791D01*
Y88436D01*
X30803D01*
Y88447D01*
X30814D01*
Y88470D01*
X30825D01*
Y88481D01*
X30837D01*
Y88493D01*
X30849D01*
Y88516D01*
X30860D01*
Y88551D01*
X30872D01*
Y88574D01*
X30860D01*
Y88551D01*
X30849D01*
Y88539D01*
X30837D01*
Y88551D01*
X30825D01*
Y88574D01*
X30837D01*
Y88585D01*
X30849D01*
Y88608D01*
X30860D01*
Y88620D01*
X30872D01*
Y88631D01*
X30883D01*
Y88608D01*
X30872D01*
Y88574D01*
X30895D01*
Y88562D01*
X30906D01*
Y88620D01*
X30918D01*
Y88643D01*
X30929D01*
Y88654D01*
X30941D01*
Y88666D01*
X30952D01*
Y88689D01*
X30964D01*
Y88712D01*
X30975D01*
Y88723D01*
X30987D01*
Y88746D01*
X30998D01*
Y88793D01*
X31010D01*
Y88815D01*
X31021D01*
Y88838D01*
X31033D01*
Y88873D01*
X31044D01*
Y88896D01*
X31056D01*
Y88931D01*
X31079D01*
Y88942D01*
X31090D01*
Y89011D01*
X31102D01*
Y88988D01*
X31113D01*
Y89000D01*
X31125D01*
Y89023D01*
X31137D01*
Y89034D01*
X31113D01*
Y89023D01*
X31102D01*
Y89092D01*
X31079D01*
Y89080D01*
X31056D01*
Y89069D01*
X31044D01*
Y89057D01*
X31056D01*
Y89023D01*
X31033D01*
Y89011D01*
X31021D01*
Y88988D01*
X31010D01*
Y88965D01*
X30998D01*
Y89000D01*
X30987D01*
Y89034D01*
X30998D01*
Y89046D01*
X31021D01*
Y89069D01*
X31010D01*
Y89080D01*
X31021D01*
Y89092D01*
X31033D01*
Y89115D01*
X31044D01*
Y89161D01*
X31056D01*
Y89173D01*
X31067D01*
Y89184D01*
X31079D01*
Y89207D01*
X31090D01*
Y89265D01*
X31102D01*
Y89276D01*
X31137D01*
Y89288D01*
X31125D01*
Y89311D01*
X31137D01*
Y89322D01*
X31148D01*
Y89334D01*
X31159D01*
Y89345D01*
X31183D01*
Y89357D01*
X31194D01*
Y89368D01*
X31183D01*
Y89380D01*
X31194D01*
Y89391D01*
X31206D01*
Y89449D01*
X31229D01*
Y89460D01*
X31206D01*
Y89495D01*
X31217D01*
Y89507D01*
X31229D01*
Y89483D01*
X31240D01*
Y89495D01*
X31252D01*
Y89507D01*
X31229D01*
Y89518D01*
X31217D01*
Y89530D01*
X31206D01*
Y89541D01*
X31229D01*
Y89553D01*
X31240D01*
Y89587D01*
X31229D01*
Y89610D01*
X31240D01*
Y89645D01*
X31252D01*
Y89656D01*
X31275D01*
Y89668D01*
X31286D01*
Y89679D01*
X31275D01*
Y89691D01*
X31298D01*
Y89679D01*
X31309D01*
Y89714D01*
X31321D01*
Y89702D01*
X31332D01*
Y89679D01*
X31344D01*
Y89702D01*
X31367D01*
Y89714D01*
X31378D01*
Y89725D01*
X31367D01*
Y89737D01*
X31378D01*
Y89748D01*
X31355D01*
Y89737D01*
X31344D01*
Y89714D01*
X31332D01*
Y89725D01*
X31321D01*
Y89783D01*
X31332D01*
Y89794D01*
X31344D01*
Y89829D01*
X31217D01*
Y89841D01*
X31206D01*
Y89852D01*
D02*
G37*
G36*
X30929Y89841D02*
X30918D01*
Y89829D01*
X30929D01*
Y89841D01*
D02*
G37*
G36*
X30595Y89817D02*
X30572D01*
Y89794D01*
X30595D01*
Y89817D01*
D02*
G37*
G36*
X31424Y89829D02*
X31390D01*
Y89783D01*
X31413D01*
Y89817D01*
X31424D01*
Y89829D01*
D02*
G37*
G36*
X26910Y89783D02*
X26875D01*
Y89771D01*
X26910D01*
Y89783D01*
D02*
G37*
G36*
X31390D02*
X31378D01*
Y89771D01*
X31390D01*
Y89760D01*
X31401D01*
Y89771D01*
X31390D01*
Y89783D01*
D02*
G37*
G36*
X26806Y89748D02*
X26795D01*
Y89737D01*
X26806Y89725D01*
X26829D01*
Y89737D01*
X26806D01*
Y89748D01*
D02*
G37*
G36*
X26760Y89737D02*
X26749D01*
Y89725D01*
X26760D01*
Y89737D01*
D02*
G37*
G36*
X26898D02*
X26875D01*
Y89725D01*
X26887D01*
Y89714D01*
X26910D01*
Y89725D01*
X26898D01*
Y89737D01*
D02*
G37*
G36*
X31563Y89886D02*
X31528D01*
Y89875D01*
X31517D01*
Y89852D01*
X31505D01*
Y89841D01*
X31493D01*
Y89829D01*
X31482D01*
Y89806D01*
X31471D01*
Y89783D01*
X31447D01*
Y89748D01*
X31436D01*
Y89725D01*
X31413D01*
Y89702D01*
X31424D01*
Y89691D01*
X31436D01*
Y89702D01*
X31447D01*
Y89714D01*
X31459D01*
Y89737D01*
X31471D01*
Y89748D01*
X31493D01*
Y89760D01*
X31505D01*
Y89771D01*
X31517D01*
Y89783D01*
X31528D01*
Y89817D01*
X31540D01*
Y89829D01*
X31563D01*
Y89841D01*
X31574D01*
Y89864D01*
X31551D01*
Y89875D01*
X31563D01*
Y89886D01*
D02*
G37*
G36*
X26806Y89691D02*
X26795D01*
Y89679D01*
X26806D01*
Y89691D01*
D02*
G37*
G36*
X30008Y89679D02*
X29973D01*
Y89668D01*
X30008D01*
Y89679D01*
D02*
G37*
G36*
X31424D02*
X31390D01*
Y89645D01*
X31401D01*
Y89656D01*
X31413D01*
Y89668D01*
X31424D01*
Y89679D01*
D02*
G37*
G36*
X25896Y89645D02*
X25885D01*
Y89633D01*
X25896D01*
Y89645D01*
D02*
G37*
G36*
X31332Y89656D02*
X31321D01*
Y89645D01*
X31309D01*
Y89633D01*
X31298D01*
Y89622D01*
X31321D01*
Y89633D01*
X31332D01*
Y89656D01*
D02*
G37*
G36*
X31275Y89633D02*
X31263D01*
Y89622D01*
X31275D01*
Y89633D01*
D02*
G37*
G36*
X30031D02*
X30019D01*
Y89622D01*
X30031D01*
Y89633D01*
D02*
G37*
G36*
X31252Y89599D02*
X31240D01*
Y89587D01*
X31252D01*
Y89599D01*
D02*
G37*
G36*
X31390Y89645D02*
X31378D01*
Y89622D01*
X31367D01*
Y89610D01*
X31355D01*
Y89599D01*
X31344D01*
Y89564D01*
X31355D01*
Y89576D01*
X31367D01*
Y89587D01*
X31378D01*
Y89610D01*
X31390D01*
Y89645D01*
D02*
G37*
G36*
X31286Y89576D02*
X31275D01*
Y89564D01*
X31263D01*
Y89553D01*
X31252D01*
Y89541D01*
X31275D01*
Y89553D01*
X31286D01*
Y89576D01*
D02*
G37*
G36*
X30008Y89610D02*
X29996D01*
Y89599D01*
X30008D01*
Y89564D01*
X29996D01*
Y89541D01*
X30008D01*
Y89553D01*
X30019D01*
Y89599D01*
X30008D01*
Y89610D01*
D02*
G37*
G36*
X31263Y89518D02*
X31252D01*
Y89507D01*
X31263D01*
Y89518D01*
D02*
G37*
G36*
X29605Y89460D02*
X29593D01*
Y89449D01*
X29605D01*
Y89460D01*
D02*
G37*
G36*
X25655Y89449D02*
X25643D01*
Y89437D01*
X25655D01*
Y89449D01*
D02*
G37*
G36*
X31344Y89564D02*
X31332D01*
Y89541D01*
X31321D01*
Y89518D01*
X31309D01*
Y89507D01*
X31298D01*
Y89483D01*
X31286D01*
Y89449D01*
X31275D01*
Y89437D01*
X31263D01*
Y89414D01*
X31252D01*
Y89403D01*
X31286D01*
Y89414D01*
Y89426D01*
X31298D01*
Y89449D01*
X31309D01*
Y89472D01*
X31321D01*
Y89507D01*
X31344D01*
Y89541D01*
X31355D01*
Y89553D01*
X31344D01*
Y89564D01*
D02*
G37*
G36*
X29697Y89414D02*
X29685D01*
Y89403D01*
X29697D01*
Y89414D01*
D02*
G37*
G36*
X28603Y89403D02*
X28591D01*
Y89391D01*
X28603D01*
Y89403D01*
D02*
G37*
G36*
X31252Y89391D02*
X31240D01*
Y89368D01*
X31252D01*
Y89380D01*
Y89391D01*
D02*
G37*
G36*
X28684Y89426D02*
X28660D01*
Y89403D01*
X28649D01*
Y89391D01*
X28626D01*
Y89380D01*
X28603D01*
Y89368D01*
X28591D01*
Y89380D01*
X28545D01*
Y89368D01*
X28534D01*
Y89357D01*
X28476D01*
Y89345D01*
X28407D01*
Y89334D01*
X28372D01*
Y89322D01*
X28350D01*
Y89311D01*
X28315D01*
Y89299D01*
X28257D01*
Y89288D01*
X28246D01*
Y89276D01*
X28234D01*
Y89207D01*
X28246D01*
Y89161D01*
X28257D01*
Y89149D01*
X28246D01*
Y89126D01*
X28234D01*
Y89103D01*
X28246D01*
Y89080D01*
X28257D01*
Y89057D01*
X28269D01*
Y89023D01*
X28257D01*
Y89000D01*
X28269D01*
Y88931D01*
X28280D01*
Y88793D01*
X28292D01*
Y88493D01*
X28303D01*
Y88481D01*
X28315D01*
Y88424D01*
X28303D01*
Y88401D01*
X28292D01*
Y88389D01*
X28303D01*
Y88378D01*
X28326D01*
Y88228D01*
X28350D01*
Y88217D01*
X28326D01*
Y88205D01*
X28315D01*
Y88182D01*
X28326D01*
Y88194D01*
X28338D01*
Y88171D01*
X28361D01*
Y88217D01*
X28372D01*
Y88263D01*
X28384D01*
Y88286D01*
X28396D01*
Y88309D01*
X28407D01*
Y88343D01*
X28419D01*
Y88332D01*
X28430D01*
Y88355D01*
X28419D01*
Y88378D01*
X28442D01*
Y88389D01*
X28453D01*
Y88412D01*
X28442D01*
Y88401D01*
X28419D01*
Y88436D01*
X28430D01*
Y88447D01*
X28442D01*
Y88436D01*
X28453D01*
Y88424D01*
X28465D01*
Y88447D01*
X28453D01*
Y88459D01*
X28442D01*
Y88470D01*
X28430D01*
Y88481D01*
X28419D01*
Y88528D01*
X28430D01*
Y88516D01*
X28442D01*
Y88505D01*
X28453D01*
Y88493D01*
X28465D01*
Y88505D01*
X28453D01*
Y88516D01*
X28465D01*
Y88528D01*
X28476D01*
Y88539D01*
X28488D01*
Y88551D01*
X28476D01*
Y88562D01*
X28465D01*
Y88574D01*
X28476D01*
Y88585D01*
X28488D01*
Y88597D01*
X28499D01*
Y88608D01*
X28488D01*
Y88620D01*
X28476D01*
Y88631D01*
X28465D01*
Y88643D01*
X28453D01*
Y88654D01*
X28465D01*
Y88700D01*
X28476D01*
Y88666D01*
X28488D01*
Y88654D01*
X28499D01*
Y88700D01*
X28511D01*
Y88758D01*
X28522D01*
Y88723D01*
X28534D01*
Y88712D01*
X28568D01*
Y88735D01*
X28545D01*
Y88758D01*
X28534D01*
Y88793D01*
X28568D01*
Y88815D01*
X28557D01*
Y88827D01*
X28511D01*
Y88804D01*
X28522D01*
Y88793D01*
X28511D01*
Y88781D01*
X28499D01*
Y88769D01*
X28488D01*
Y88793D01*
X28499D01*
Y88838D01*
X28522D01*
Y88873D01*
X28545D01*
Y88838D01*
X28568D01*
Y88862D01*
X28557D01*
Y88885D01*
X28545D01*
Y88908D01*
X28534D01*
Y88931D01*
X28545D01*
Y88977D01*
X28557D01*
Y88965D01*
X28568D01*
Y88977D01*
X28557D01*
Y88988D01*
X28568D01*
Y89011D01*
X28557D01*
Y89046D01*
X28568D01*
Y89069D01*
X28580D01*
Y89080D01*
X28568D01*
Y89092D01*
X28580D01*
Y89103D01*
X28591D01*
Y89138D01*
X28603D01*
Y89126D01*
X28614D01*
Y89184D01*
X28626D01*
Y89196D01*
X28637D01*
Y89219D01*
X28649D01*
Y89230D01*
X28637D01*
Y89253D01*
X28649D01*
Y89276D01*
X28660D01*
Y89299D01*
X28649D01*
Y89311D01*
X28637D01*
Y89322D01*
X28649D01*
Y89334D01*
X28660D01*
Y89345D01*
X28672D01*
Y89368D01*
X28660D01*
Y89391D01*
X28672D01*
Y89403D01*
X28684D01*
Y89426D01*
D02*
G37*
G36*
X31850Y89368D02*
X31839D01*
Y89357D01*
X31850D01*
Y89368D01*
D02*
G37*
G36*
X31240Y89357D02*
X31229D01*
Y89345D01*
X31240D01*
Y89357D01*
D02*
G37*
G36*
X25620Y89368D02*
X25597D01*
Y89345D01*
X25620D01*
Y89368D01*
D02*
G37*
G36*
X31240Y89299D02*
X31229D01*
Y89288D01*
X31240D01*
Y89299D01*
D02*
G37*
G36*
X31217Y89334D02*
X31206D01*
Y89322D01*
X31194D01*
Y89276D01*
X31206D01*
Y89288D01*
X31217D01*
Y89311D01*
X31229D01*
Y89322D01*
X31217D01*
Y89334D01*
D02*
G37*
G36*
X31113Y89253D02*
X31102D01*
Y89242D01*
Y89230D01*
X31113D01*
Y89253D01*
D02*
G37*
G36*
X29651Y89230D02*
X29639D01*
Y89219D01*
X29651D01*
Y89230D01*
D02*
G37*
G36*
X25505Y89219D02*
X25493D01*
Y89207D01*
X25505D01*
Y89219D01*
D02*
G37*
G36*
X31194Y89276D02*
X31171D01*
Y89265D01*
X31159D01*
Y89230D01*
X31148D01*
Y89196D01*
X31137D01*
Y89184D01*
X31113D01*
Y89196D01*
X31102D01*
Y89173D01*
X31113D01*
Y89149D01*
X31102D01*
Y89161D01*
X31090D01*
Y89138D01*
X31102D01*
Y89115D01*
X31125D01*
Y89126D01*
X31137D01*
Y89138D01*
X31148D01*
Y89173D01*
X31159D01*
Y89184D01*
X31171D01*
Y89219D01*
X31183D01*
Y89253D01*
X31194D01*
Y89276D01*
D02*
G37*
G36*
X31183Y89161D02*
X31171D01*
Y89149D01*
X31183D01*
Y89161D01*
D02*
G37*
G36*
X29766Y89126D02*
X29743D01*
Y89115D01*
Y89103D01*
X29766D01*
Y89126D01*
D02*
G37*
G36*
X31159Y89115D02*
X31137D01*
Y89092D01*
X31148D01*
Y89080D01*
X31159D01*
Y89115D01*
D02*
G37*
G36*
X31137Y89080D02*
X31125D01*
Y89069D01*
Y89057D01*
X31148D01*
Y89069D01*
X31137D01*
Y89080D01*
D02*
G37*
G36*
X27532Y89069D02*
X27520D01*
Y89057D01*
X27532D01*
Y89069D01*
D02*
G37*
G36*
X27440Y89138D02*
X27428D01*
Y89080D01*
X27440D01*
Y89069D01*
Y89057D01*
X27463D01*
Y89092D01*
X27451D01*
Y89126D01*
X27440D01*
Y89138D01*
D02*
G37*
G36*
X29789Y89046D02*
X29778D01*
Y89034D01*
X29789D01*
Y89046D01*
D02*
G37*
G36*
X27486Y89034D02*
X27474D01*
Y89023D01*
X27486D01*
Y89034D01*
D02*
G37*
G36*
X29685Y89046D02*
X29674D01*
Y89011D01*
X29685D01*
Y89034D01*
Y89046D01*
D02*
G37*
G36*
X29835Y89000D02*
X29824D01*
Y88988D01*
X29835D01*
Y89000D01*
D02*
G37*
G36*
Y88977D02*
X29824D01*
Y88965D01*
X29835D01*
Y88977D01*
D02*
G37*
G36*
X29870Y88954D02*
X29858D01*
Y88942D01*
X29870D01*
Y88954D01*
D02*
G37*
G36*
X28568Y88942D02*
X28557D01*
Y88919D01*
X28568D01*
Y88931D01*
Y88942D01*
D02*
G37*
G36*
X27624Y88931D02*
X27612D01*
Y88896D01*
X27624D01*
Y88908D01*
Y88931D01*
D02*
G37*
G36*
X29858Y88896D02*
X29835D01*
Y88873D01*
X29858D01*
Y88885D01*
Y88896D01*
D02*
G37*
G36*
X27509Y88908D02*
X27486D01*
Y88873D01*
X27509D01*
Y88908D01*
D02*
G37*
G36*
X26150Y88885D02*
X26138D01*
Y88873D01*
X26150D01*
Y88885D01*
D02*
G37*
G36*
X26069Y88850D02*
X26058D01*
Y88838D01*
X26069D01*
Y88850D01*
D02*
G37*
G36*
X27589Y88838D02*
X27578D01*
Y88827D01*
X27589D01*
Y88838D01*
D02*
G37*
G36*
X27509D02*
X27474D01*
Y88804D01*
X27497D01*
Y88815D01*
X27509D01*
Y88838D01*
D02*
G37*
G36*
X29870Y88793D02*
X29858D01*
Y88781D01*
X29870D01*
Y88793D01*
D02*
G37*
G36*
X29732D02*
X29720D01*
Y88781D01*
X29732D01*
Y88793D01*
D02*
G37*
G36*
X25539Y88804D02*
X25516D01*
Y88793D01*
X25505D01*
Y88781D01*
X25539D01*
Y88804D01*
D02*
G37*
G36*
X27532Y88781D02*
X27509D01*
Y88758D01*
X27532D01*
Y88769D01*
Y88781D01*
D02*
G37*
G36*
X25781Y88746D02*
X25770D01*
Y88735D01*
X25781D01*
Y88746D01*
D02*
G37*
G36*
X25735D02*
X25724D01*
Y88735D01*
X25735D01*
Y88746D01*
D02*
G37*
G36*
X25689D02*
X25678D01*
Y88735D01*
X25689D01*
Y88746D01*
D02*
G37*
G36*
X27520Y88735D02*
X27509D01*
Y88723D01*
X27520D01*
Y88735D01*
D02*
G37*
G36*
X25632Y88689D02*
X25620D01*
Y88677D01*
X25632D01*
Y88689D01*
D02*
G37*
G36*
X28511Y88643D02*
X28499D01*
Y88631D01*
X28511D01*
Y88643D01*
D02*
G37*
G36*
X29881Y88620D02*
X29870D01*
Y88608D01*
X29881D01*
Y88620D01*
D02*
G37*
G36*
X31471Y88608D02*
X31459D01*
Y88597D01*
X31471D01*
Y88608D01*
D02*
G37*
G36*
X27635D02*
X27624D01*
Y88597D01*
X27635D01*
Y88608D01*
D02*
G37*
G36*
X28511Y88574D02*
X28499D01*
Y88562D01*
X28511D01*
Y88574D01*
D02*
G37*
G36*
X29881Y88562D02*
X29870D01*
Y88551D01*
X29881D01*
Y88562D01*
D02*
G37*
G36*
X27532Y88689D02*
X27520D01*
Y88551D01*
X27555D01*
Y88574D01*
X27543D01*
Y88585D01*
X27532D01*
Y88689D01*
D02*
G37*
G36*
X29962Y88551D02*
X29927D01*
Y88539D01*
X29939D01*
Y88528D01*
X29950D01*
Y88539D01*
X29962D01*
Y88551D01*
D02*
G37*
G36*
X29075Y88562D02*
X29063D01*
Y88528D01*
X29087D01*
Y88539D01*
Y88551D01*
X29075D01*
Y88562D01*
D02*
G37*
G36*
X29870Y88528D02*
X29858D01*
Y88516D01*
X29870D01*
Y88528D01*
D02*
G37*
G36*
X29133Y88481D02*
X29121D01*
Y88470D01*
X29133D01*
Y88481D01*
D02*
G37*
G36*
X29973Y88505D02*
X29962D01*
Y88481D01*
Y88470D01*
Y88459D01*
X29973D01*
Y88505D01*
D02*
G37*
G36*
X27659Y88516D02*
X27647D01*
Y88505D01*
X27635D01*
Y88493D01*
X27647D01*
Y88447D01*
X27670D01*
Y88505D01*
X27659D01*
Y88516D01*
D02*
G37*
G36*
Y88424D02*
X27647D01*
Y88412D01*
X27659D01*
Y88424D01*
D02*
G37*
G36*
X29893Y88332D02*
X29881D01*
Y88320D01*
X29893D01*
Y88332D01*
D02*
G37*
G36*
X27555Y88424D02*
X27532D01*
Y88320D01*
X27555D01*
Y88424D01*
D02*
G37*
G36*
X28994Y88309D02*
X28983D01*
Y88286D01*
X28994D01*
Y88309D01*
D02*
G37*
G36*
X29916Y88286D02*
X29904D01*
Y88274D01*
Y88263D01*
X29916D01*
Y88286D01*
D02*
G37*
G36*
X28419D02*
X28407D01*
Y88274D01*
Y88263D01*
X28419D01*
Y88286D01*
D02*
G37*
G36*
X27693Y88378D02*
X27670D01*
Y88332D01*
X27659D01*
Y88320D01*
X27670D01*
Y88274D01*
X27659D01*
Y88263D01*
X27670D01*
Y88228D01*
X27681D01*
Y88240D01*
X27693D01*
Y88378D01*
D02*
G37*
G36*
X28407Y88240D02*
X28384D01*
Y88217D01*
X28407D01*
Y88240D01*
D02*
G37*
G36*
X27659Y88228D02*
X27647D01*
Y88217D01*
X27659D01*
Y88228D01*
D02*
G37*
G36*
X30572D02*
X30549D01*
Y88217D01*
Y88205D01*
X30572D01*
Y88228D01*
D02*
G37*
G36*
X27566Y88263D02*
X27555D01*
Y88205D01*
X27566D01*
Y88240D01*
Y88251D01*
Y88263D01*
D02*
G37*
G36*
X30595Y88217D02*
X30584D01*
Y88182D01*
X30595D01*
Y88194D01*
X30607D01*
Y88205D01*
X30595D01*
Y88217D01*
D02*
G37*
G36*
X29927Y88228D02*
X29916D01*
Y88159D01*
Y88148D01*
X29927D01*
Y88136D01*
X29950D01*
Y88148D01*
X29939D01*
Y88159D01*
X29927D01*
Y88228D01*
D02*
G37*
G36*
X28326Y88171D02*
X28315D01*
Y88159D01*
Y88148D01*
Y88136D01*
X28326D01*
Y88171D01*
D02*
G37*
G36*
X31194Y88136D02*
X31183D01*
Y88125D01*
X31194D01*
Y88136D01*
D02*
G37*
G36*
X30019D02*
X30008D01*
Y88125D01*
X30019D01*
Y88136D01*
D02*
G37*
G36*
X30538Y88148D02*
X30526D01*
Y88113D01*
X30538D01*
Y88125D01*
Y88136D01*
Y88148D01*
D02*
G37*
G36*
X28326Y88125D02*
X28315D01*
Y88113D01*
X28326D01*
Y88125D01*
D02*
G37*
G36*
X29939D02*
X29927D01*
Y88113D01*
Y88090D01*
X29939D01*
Y88102D01*
X29950D01*
Y88113D01*
X29939D01*
Y88125D01*
D02*
G37*
G36*
X27705Y88182D02*
X27670D01*
Y88136D01*
X27681D01*
Y88102D01*
X27693D01*
Y88090D01*
X27705D01*
Y88182D01*
D02*
G37*
G36*
X30526Y88113D02*
X30515D01*
Y88102D01*
X30503D01*
Y88067D01*
X30526D01*
Y88113D01*
D02*
G37*
G36*
X30042Y88102D02*
X30019D01*
Y88078D01*
Y88067D01*
X30042D01*
Y88102D01*
D02*
G37*
G36*
X30503Y88044D02*
X30492D01*
Y88032D01*
X30503D01*
Y88044D01*
D02*
G37*
G36*
X27578Y88102D02*
X27566D01*
Y88090D01*
Y88078D01*
Y88032D01*
X27578D01*
Y88102D01*
D02*
G37*
G36*
X29939Y88078D02*
X29927D01*
Y88044D01*
X29950D01*
Y88009D01*
X29962D01*
Y87998D01*
X29973D01*
Y88021D01*
Y88032D01*
Y88044D01*
X29962D01*
Y88055D01*
X29950D01*
Y88067D01*
X29939D01*
Y88078D01*
D02*
G37*
G36*
X30054Y88009D02*
X30031D01*
Y87998D01*
Y87986D01*
X30054D01*
Y88009D01*
D02*
G37*
G36*
X27705Y88078D02*
X27693D01*
Y88067D01*
X27681D01*
Y88044D01*
X27693D01*
Y88032D01*
X27681D01*
Y87998D01*
X27693D01*
Y87975D01*
X27716D01*
Y88021D01*
X27705D01*
Y88067D01*
Y88078D01*
D02*
G37*
G36*
X29985Y87963D02*
X29973D01*
Y87952D01*
X29985D01*
Y87963D01*
D02*
G37*
G36*
X29259D02*
X29248D01*
Y87952D01*
X29259D01*
Y87963D01*
D02*
G37*
G36*
X27612Y87952D02*
X27601D01*
Y87940D01*
X27612D01*
Y87952D01*
D02*
G37*
G36*
X30526Y87940D02*
X30515D01*
Y87929D01*
X30480D01*
Y87906D01*
X30503D01*
Y87917D01*
X30526D01*
Y87906D01*
X30538D01*
Y87929D01*
X30526D01*
Y87940D01*
D02*
G37*
G36*
X29985D02*
X29962D01*
Y87917D01*
X29973D01*
Y87906D01*
X29985D01*
Y87917D01*
X29996D01*
Y87929D01*
X29985D01*
Y87940D01*
D02*
G37*
G36*
X30480Y87894D02*
X30468D01*
Y87883D01*
X30457D01*
Y87871D01*
X30468D01*
Y87860D01*
X30480D01*
Y87894D01*
D02*
G37*
G36*
X27716Y87860D02*
X27705D01*
Y87814D01*
X27716D01*
Y87848D01*
Y87860D01*
D02*
G37*
G36*
X30457Y87814D02*
X30446D01*
Y87802D01*
X30457D01*
Y87814D01*
D02*
G37*
G36*
X27532Y87756D02*
X27520D01*
Y87744D01*
X27532D01*
Y87756D01*
D02*
G37*
G36*
X27751Y87779D02*
X27728D01*
Y87767D01*
Y87756D01*
Y87733D01*
X27751D01*
Y87779D01*
D02*
G37*
G36*
X27532Y87721D02*
X27520D01*
Y87710D01*
X27532D01*
Y87721D01*
D02*
G37*
G36*
X27543Y87675D02*
X27532D01*
Y87664D01*
X27543D01*
Y87675D01*
D02*
G37*
G36*
X27739D02*
X27716D01*
Y87652D01*
X27739D01*
Y87675D01*
D02*
G37*
G36*
X27762Y87618D02*
X27751D01*
Y87606D01*
X27762D01*
Y87618D01*
D02*
G37*
G36*
X27751Y87560D02*
X27739D01*
Y87549D01*
X27751D01*
Y87560D01*
D02*
G37*
G36*
X30330Y87549D02*
X30319D01*
Y87537D01*
X30307D01*
Y87526D01*
X30342D01*
Y87537D01*
X30330D01*
Y87549D01*
D02*
G37*
G36*
X27751Y87491D02*
X27739D01*
Y87480D01*
X27751D01*
Y87491D01*
D02*
G37*
G36*
X27681D02*
X27670D01*
Y87480D01*
X27681D01*
Y87491D01*
D02*
G37*
G36*
X27774Y87457D02*
X27751D01*
Y87422D01*
Y87410D01*
Y87388D01*
X27774D01*
Y87399D01*
X27785D01*
Y87445D01*
X27774D01*
Y87457D01*
D02*
G37*
G36*
X28614Y87249D02*
X28603D01*
Y87238D01*
X28614D01*
Y87249D01*
D02*
G37*
G36*
X27797Y87284D02*
X27785D01*
Y87272D01*
X27774D01*
Y87249D01*
X27785D01*
Y87238D01*
X27797D01*
Y87249D01*
Y87284D01*
D02*
G37*
G36*
X27785Y87215D02*
X27762D01*
Y87192D01*
X27774D01*
Y87203D01*
X27785D01*
Y87215D01*
D02*
G37*
G36*
X27739Y87157D02*
X27716D01*
Y87146D01*
X27739D01*
Y87157D01*
D02*
G37*
G36*
X28557Y87111D02*
X28545D01*
Y87099D01*
X28557D01*
Y87111D01*
D02*
G37*
G36*
X27808Y87192D02*
X27797D01*
Y87088D01*
X27808D01*
Y87146D01*
Y87157D01*
Y87192D01*
D02*
G37*
G36*
X27728Y87088D02*
X27716D01*
Y87076D01*
X27728D01*
Y87088D01*
D02*
G37*
G36*
X27797D02*
X27762D01*
Y87076D01*
X27774D01*
Y87042D01*
X27797D01*
Y87088D01*
D02*
G37*
G36*
X28522Y87007D02*
X28511D01*
Y86996D01*
X28522D01*
Y87007D01*
D02*
G37*
G36*
X27820D02*
X27797D01*
Y86984D01*
X27785D01*
Y86973D01*
X27774D01*
Y86961D01*
X27785D01*
Y86950D01*
X27808D01*
Y86973D01*
X27820D01*
Y86984D01*
X27831D01*
Y86996D01*
X27820D01*
Y87007D01*
D02*
G37*
G36*
X27751Y87042D02*
X27739D01*
Y87030D01*
X27728D01*
Y86996D01*
X27751D01*
Y86984D01*
X27739D01*
Y86973D01*
X27728D01*
Y86961D01*
X27739D01*
Y86950D01*
X27751D01*
Y86973D01*
X27762D01*
Y86996D01*
X27751D01*
Y87042D01*
D02*
G37*
G36*
X30710Y86961D02*
X30687D01*
Y86938D01*
X30710D01*
Y86961D01*
D02*
G37*
G36*
X27762Y86904D02*
X27751D01*
Y86892D01*
X27762D01*
Y86904D01*
D02*
G37*
G36*
Y86858D02*
X27751D01*
Y86846D01*
X27762D01*
Y86858D01*
D02*
G37*
G36*
X27866Y86823D02*
X27854D01*
Y86812D01*
X27866D01*
Y86823D01*
D02*
G37*
G36*
X28430Y86812D02*
X28419D01*
Y86800D01*
X28430D01*
Y86812D01*
D02*
G37*
G36*
X27820Y86892D02*
X27797D01*
Y86869D01*
X27808D01*
Y86800D01*
X27843D01*
Y86823D01*
X27831D01*
Y86881D01*
X27820D01*
Y86892D01*
D02*
G37*
G36*
X29732Y86800D02*
X29720D01*
Y86777D01*
X29732D01*
Y86789D01*
Y86800D01*
D02*
G37*
G36*
X28419Y86777D02*
X28407D01*
Y86766D01*
X28419D01*
Y86777D01*
D02*
G37*
G36*
X27854D02*
X27820D01*
Y86754D01*
X27843D01*
Y86766D01*
X27854D01*
Y86777D01*
D02*
G37*
G36*
X27797Y86743D02*
X27785D01*
Y86731D01*
X27797D01*
Y86743D01*
D02*
G37*
G36*
X29743Y86731D02*
X29732D01*
Y86708D01*
X29743D01*
Y86731D01*
D02*
G37*
G36*
X29732Y86662D02*
X29708D01*
Y86650D01*
X29697D01*
Y86616D01*
X29720D01*
Y86639D01*
X29732D01*
Y86662D01*
D02*
G37*
G36*
X29778Y86696D02*
X29754D01*
Y86673D01*
X29766D01*
Y86639D01*
X29754D01*
Y86627D01*
X29743D01*
Y86604D01*
X29766D01*
Y86627D01*
X29778D01*
Y86696D01*
D02*
G37*
G36*
X27705Y86581D02*
X27693D01*
Y86570D01*
X27705D01*
Y86581D01*
D02*
G37*
G36*
X28292Y86570D02*
X28269D01*
Y86558D01*
X28257D01*
Y86547D01*
X28246D01*
Y86535D01*
X28234D01*
Y86524D01*
X28257D01*
Y86535D01*
X28269D01*
Y86547D01*
X28292D01*
Y86570D01*
D02*
G37*
G36*
X27808Y86535D02*
X27797D01*
Y86524D01*
X27808D01*
Y86535D01*
D02*
G37*
G36*
X29754Y86512D02*
X29732D01*
Y86489D01*
X29754D01*
Y86512D01*
D02*
G37*
G36*
X28004Y86501D02*
X27992D01*
Y86489D01*
X28004D01*
Y86501D01*
D02*
G37*
G36*
X28177Y86489D02*
X28165D01*
Y86478D01*
X28177D01*
Y86489D01*
D02*
G37*
G36*
X27958D02*
X27946D01*
Y86478D01*
X27958D01*
Y86489D01*
D02*
G37*
G36*
X27728Y86478D02*
X27716D01*
Y86466D01*
X27728D01*
Y86478D01*
D02*
G37*
G36*
X29743D02*
X29732D01*
Y86443D01*
X29743D01*
Y86478D01*
D02*
G37*
G36*
X28038Y86455D02*
X28027D01*
Y86443D01*
X28038D01*
Y86455D01*
D02*
G37*
G36*
X27935Y86489D02*
X27900D01*
Y86478D01*
Y86466D01*
Y86443D01*
X27912D01*
Y86455D01*
X27923D01*
Y86478D01*
X27935D01*
Y86489D01*
D02*
G37*
G36*
X28085Y86443D02*
X28073D01*
Y86432D01*
X28085D01*
Y86443D01*
D02*
G37*
G36*
X28004D02*
X27992D01*
Y86432D01*
X28004D01*
Y86443D01*
D02*
G37*
G36*
X29766Y86397D02*
X29743D01*
Y86386D01*
X29766D01*
Y86397D01*
D02*
G37*
G36*
X29754Y86339D02*
X29732D01*
Y86328D01*
Y86293D01*
X29743D01*
Y86305D01*
X29754D01*
Y86316D01*
X29766D01*
Y86328D01*
X29754D01*
Y86339D01*
D02*
G37*
G36*
X29789Y86305D02*
X29778D01*
Y86282D01*
X29789D01*
Y86293D01*
Y86305D01*
D02*
G37*
G36*
X29778Y86259D02*
X29766D01*
Y86236D01*
X29754D01*
Y86201D01*
X29766D01*
Y86190D01*
X29754D01*
Y86132D01*
X29766D01*
Y86121D01*
X29778D01*
Y86155D01*
X29789D01*
Y86201D01*
X29778D01*
Y86259D01*
D02*
G37*
G36*
X30365Y86121D02*
X30353D01*
Y86109D01*
X30365D01*
Y86121D01*
D02*
G37*
G36*
X29801Y86063D02*
X29789D01*
Y86051D01*
X29801D01*
Y86063D01*
D02*
G37*
G36*
X29778Y85982D02*
X29766D01*
Y85971D01*
X29778D01*
Y85982D01*
D02*
G37*
G36*
X29824Y85775D02*
X29812D01*
Y85764D01*
X29824D01*
Y85775D01*
D02*
G37*
G36*
Y85706D02*
X29812D01*
Y85694D01*
X29824D01*
Y85706D01*
D02*
G37*
G36*
Y85614D02*
X29801D01*
Y85602D01*
X29812D01*
Y85591D01*
X29824D01*
Y85602D01*
Y85614D01*
D02*
G37*
G36*
X30065Y85499D02*
X30054D01*
Y85487D01*
X30065D01*
Y85499D01*
D02*
G37*
G36*
Y85464D02*
X30054D01*
Y85453D01*
X30065D01*
Y85464D01*
D02*
G37*
G36*
X29927Y85372D02*
X29916D01*
Y85349D01*
X29927D01*
Y85372D01*
D02*
G37*
%LPD*%
G36*
X28419Y96152D02*
Y96140D01*
Y96117D01*
X28407D01*
Y96175D01*
X28419D01*
Y96152D01*
D02*
G37*
G36*
X27163Y91614D02*
X27152D01*
Y91591D01*
X27140D01*
Y91625D01*
X27163D01*
Y91614D01*
D02*
G37*
G36*
X27152Y91464D02*
Y91453D01*
X27140D01*
Y91487D01*
X27152D01*
Y91464D01*
D02*
G37*
G36*
X28557Y91176D02*
X28545D01*
Y91199D01*
X28557D01*
Y91176D01*
D02*
G37*
G36*
X28614Y90900D02*
X28603D01*
Y90865D01*
Y90854D01*
Y90842D01*
X28591D01*
Y90912D01*
X28614D01*
Y90900D01*
D02*
G37*
G36*
X28591Y90727D02*
X28568D01*
Y90739D01*
X28591D01*
Y90727D01*
D02*
G37*
G36*
X28534Y90716D02*
X28499D01*
Y90727D01*
X28534D01*
Y90716D01*
D02*
G37*
G36*
X28499Y90635D02*
X28476D01*
Y90647D01*
X28499D01*
Y90635D01*
D02*
G37*
G36*
X28211D02*
X28188D01*
Y90647D01*
X28211D01*
Y90635D01*
D02*
G37*
G36*
X28246Y90485D02*
X28223D01*
Y90497D01*
X28246D01*
Y90485D01*
D02*
G37*
G36*
X32472Y91096D02*
X32461D01*
Y91107D01*
X32472D01*
Y91096D01*
D02*
G37*
G36*
X32231Y91084D02*
X32219D01*
Y91096D01*
X32231D01*
Y91084D01*
D02*
G37*
G36*
X31413Y91027D02*
X31401D01*
Y91038D01*
X31413D01*
Y91027D01*
D02*
G37*
G36*
X26967Y90992D02*
X26956D01*
Y91004D01*
X26967D01*
Y90992D01*
D02*
G37*
G36*
X26956Y90958D02*
X26945D01*
Y90969D01*
Y90992D01*
X26956D01*
Y90958D01*
D02*
G37*
G36*
Y90773D02*
X26945D01*
Y90785D01*
X26956D01*
Y90773D01*
D02*
G37*
G36*
X26875Y90716D02*
X26852D01*
Y90727D01*
X26875D01*
Y90716D01*
D02*
G37*
G36*
X30365Y89737D02*
X30307D01*
Y89748D01*
X30365D01*
Y89737D01*
D02*
G37*
G36*
X30077Y89679D02*
X30065D01*
Y89702D01*
X30077D01*
Y89679D01*
D02*
G37*
G36*
X31159Y89426D02*
X31148D01*
Y89437D01*
X31159D01*
Y89426D01*
D02*
G37*
G36*
X31171Y89403D02*
X31183D01*
Y89391D01*
X31171D01*
Y89357D01*
X31159D01*
Y89368D01*
X31148D01*
Y89391D01*
X31137D01*
Y89414D01*
X31148D01*
Y89403D01*
X31159D01*
Y89414D01*
X31171D01*
Y89403D01*
D02*
G37*
G36*
X30112Y89391D02*
X30100D01*
Y89414D01*
X30112D01*
Y89391D01*
D02*
G37*
G36*
X30077Y89414D02*
Y89403D01*
Y89391D01*
X30065D01*
Y89449D01*
X30077D01*
Y89414D01*
D02*
G37*
G36*
X31137Y89368D02*
Y89357D01*
Y89345D01*
X31125D01*
Y89334D01*
X31113D01*
Y89311D01*
X31102D01*
Y89299D01*
X31090D01*
Y89322D01*
X31102D01*
Y89368D01*
X31113D01*
Y89380D01*
X31137D01*
Y89368D01*
D02*
G37*
G36*
X30123Y89322D02*
Y89311D01*
Y89299D01*
X30112D01*
Y89345D01*
X30123D01*
Y89322D01*
D02*
G37*
G36*
X31090Y89276D02*
X31079D01*
Y89288D01*
X31090D01*
Y89276D01*
D02*
G37*
G36*
X31067Y89242D02*
X31056D01*
Y89253D01*
Y89265D01*
X31067D01*
Y89242D01*
D02*
G37*
G36*
X30975Y89115D02*
Y89103D01*
X30964D01*
Y89126D01*
X30975D01*
Y89115D01*
D02*
G37*
G36*
X31010Y89080D02*
X30998D01*
Y89092D01*
Y89126D01*
X31010D01*
Y89080D01*
D02*
G37*
G36*
X30964Y89069D02*
X30952D01*
Y89080D01*
Y89092D01*
X30964D01*
Y89069D01*
D02*
G37*
G36*
X30998Y89057D02*
X30987D01*
Y89080D01*
X30998D01*
Y89057D01*
D02*
G37*
G36*
X30964Y88977D02*
X30952D01*
Y88988D01*
X30964D01*
Y88977D01*
D02*
G37*
G36*
X31056Y88965D02*
Y88954D01*
X31044D01*
Y88977D01*
X31056D01*
Y88965D01*
D02*
G37*
G36*
X30987Y88931D02*
X30964D01*
Y88942D01*
X30987D01*
Y88931D01*
D02*
G37*
G36*
X30952Y88908D02*
X30929D01*
Y88931D01*
X30952D01*
Y88908D01*
D02*
G37*
G36*
X30964Y88885D02*
X30952D01*
Y88896D01*
X30964D01*
Y88885D01*
D02*
G37*
G36*
X31044Y88896D02*
X31021D01*
Y88873D01*
X31010D01*
Y88850D01*
X30998D01*
Y88815D01*
X30987D01*
Y88804D01*
X30975D01*
Y88781D01*
X30964D01*
Y88793D01*
X30952D01*
Y88804D01*
X30964D01*
Y88838D01*
X30952D01*
Y88850D01*
X30975D01*
Y88862D01*
X30987D01*
Y88885D01*
X30998D01*
Y88919D01*
X31010D01*
Y88931D01*
Y88942D01*
X31044D01*
Y88896D01*
D02*
G37*
G36*
X30952Y88781D02*
X30941D01*
Y88793D01*
X30952D01*
Y88781D01*
D02*
G37*
G36*
X30906D02*
X30895D01*
Y88793D01*
X30906D01*
Y88781D01*
D02*
G37*
G36*
X30895Y88735D02*
X30883D01*
Y88746D01*
X30895D01*
Y88735D01*
D02*
G37*
G36*
X30825D02*
X30814D01*
Y88746D01*
X30825D01*
Y88735D01*
D02*
G37*
G36*
X30872Y88689D02*
X30860D01*
Y88700D01*
Y88712D01*
X30872D01*
Y88689D01*
D02*
G37*
G36*
X30918Y88677D02*
X30906D01*
Y88643D01*
X30895D01*
Y88689D01*
X30918D01*
Y88677D01*
D02*
G37*
G36*
X30803Y88712D02*
X30814D01*
Y88700D01*
X30825D01*
Y88677D01*
X30860D01*
Y88666D01*
X30849D01*
Y88654D01*
X30825D01*
Y88643D01*
X30837D01*
Y88620D01*
X30825D01*
Y88597D01*
X30814D01*
Y88643D01*
X30803D01*
Y88666D01*
X30814D01*
Y88689D01*
X30803D01*
Y88700D01*
X30779D01*
Y88689D01*
X30791D01*
Y88677D01*
X30768D01*
Y88654D01*
X30779D01*
Y88643D01*
X30768D01*
Y88597D01*
X30779D01*
Y88585D01*
X30768D01*
Y88597D01*
X30756D01*
Y88608D01*
X30733D01*
Y88551D01*
X30722D01*
Y88505D01*
X30733D01*
Y88493D01*
X30722D01*
Y88505D01*
X30710D01*
Y88481D01*
X30699D01*
Y88470D01*
X30687D01*
Y88424D01*
X30676D01*
Y88412D01*
X30664D01*
Y88355D01*
X30676D01*
Y88366D01*
X30699D01*
Y88343D01*
X30687D01*
Y88332D01*
X30664D01*
Y88355D01*
X30653D01*
Y88343D01*
X30641D01*
Y88320D01*
X30630D01*
Y88309D01*
X30653D01*
Y88286D01*
X30607D01*
Y88320D01*
X30618D01*
Y88332D01*
X30607D01*
Y88355D01*
X30618D01*
Y88412D01*
X30630D01*
Y88436D01*
X30641D01*
Y88447D01*
X30653D01*
Y88459D01*
X30664D01*
Y88481D01*
X30676D01*
Y88505D01*
X30664D01*
Y88516D01*
X30687D01*
Y88528D01*
X30699D01*
Y88562D01*
X30710D01*
Y88620D01*
X30733D01*
Y88654D01*
X30756D01*
Y88666D01*
X30745D01*
Y88689D01*
X30756D01*
Y88700D01*
X30768D01*
Y88723D01*
X30779D01*
Y88735D01*
X30803D01*
Y88712D01*
D02*
G37*
G36*
X30825Y88516D02*
X30814D01*
Y88528D01*
X30825D01*
Y88516D01*
D02*
G37*
G36*
X30722Y88401D02*
X30710D01*
Y88412D01*
X30722D01*
Y88401D01*
D02*
G37*
G36*
X30595Y88263D02*
X30584D01*
Y88274D01*
X30595D01*
Y88263D01*
D02*
G37*
G36*
X30584Y88021D02*
X30572D01*
Y88032D01*
X30584D01*
Y88021D01*
D02*
G37*
G36*
X30549Y87975D02*
X30538D01*
Y87986D01*
X30549D01*
Y87975D01*
D02*
G37*
G36*
X28626Y89265D02*
X28614D01*
Y89276D01*
X28626D01*
Y89265D01*
D02*
G37*
G36*
X28488Y88746D02*
Y88723D01*
X28465D01*
Y88758D01*
X28488D01*
Y88746D01*
D02*
G37*
G36*
X28326Y88700D02*
Y88689D01*
X28315D01*
Y88712D01*
X28326D01*
Y88700D01*
D02*
G37*
G36*
X28465Y88608D02*
Y88597D01*
Y88585D01*
X28453D01*
Y88620D01*
X28465D01*
Y88608D01*
D02*
G37*
G36*
X28453Y88551D02*
X28465D01*
Y88539D01*
X28453D01*
Y88551D01*
X28442D01*
Y88562D01*
Y88574D01*
X28453D01*
Y88551D01*
D02*
G37*
%LPC*%
G36*
X30307Y94827D02*
X30296D01*
Y94816D01*
X30307D01*
Y94827D01*
D02*
G37*
G36*
X30284Y94793D02*
X30250D01*
Y94770D01*
X30284D01*
Y94793D01*
D02*
G37*
G36*
X30204Y94712D02*
X30192D01*
Y94700D01*
X30169D01*
Y94689D01*
X30158D01*
Y94677D01*
X30169D01*
Y94666D01*
X30192D01*
Y94689D01*
X30204D01*
Y94712D01*
D02*
G37*
G36*
X30146Y94620D02*
X30135D01*
Y94608D01*
X30146D01*
Y94620D01*
D02*
G37*
G36*
X30112Y94585D02*
X30100D01*
Y94574D01*
X30112D01*
Y94585D01*
D02*
G37*
G36*
X30065Y94528D02*
X30054D01*
Y94516D01*
X30065D01*
Y94528D01*
D02*
G37*
G36*
X30054Y94516D02*
X30042D01*
Y94505D01*
X30031D01*
Y94493D01*
X30054D01*
Y94505D01*
Y94516D01*
D02*
G37*
G36*
X30031Y94493D02*
X30019D01*
Y94482D01*
X30031D01*
Y94493D01*
D02*
G37*
G36*
X29962Y94459D02*
X29950D01*
Y94447D01*
X29962D01*
Y94459D01*
D02*
G37*
G36*
X29916Y94389D02*
X29904D01*
Y94378D01*
X29916D01*
Y94389D01*
D02*
G37*
G36*
Y94332D02*
X29904D01*
Y94320D01*
X29916D01*
Y94332D01*
D02*
G37*
G36*
X29847Y94309D02*
X29835D01*
Y94297D01*
X29847D01*
Y94309D01*
D02*
G37*
G36*
X29870Y94274D02*
X29847D01*
Y94263D01*
X29835D01*
Y94251D01*
X29858D01*
Y94263D01*
X29870D01*
Y94274D01*
D02*
G37*
G36*
X29835Y94251D02*
X29824D01*
Y94240D01*
X29835D01*
Y94251D01*
D02*
G37*
G36*
X29824Y94217D02*
X29801D01*
Y94194D01*
X29824D01*
Y94205D01*
Y94217D01*
D02*
G37*
G36*
X29732Y94067D02*
X29720D01*
Y94055D01*
X29732D01*
Y94067D01*
D02*
G37*
G36*
X29639Y93986D02*
X29628D01*
Y93975D01*
X29639D01*
Y93986D01*
D02*
G37*
G36*
X26910Y94436D02*
X26898D01*
Y94424D01*
X26910D01*
Y94436D01*
D02*
G37*
G36*
X28119Y92132D02*
X28096D01*
Y92121D01*
X28085D01*
Y92098D01*
X28096D01*
Y92109D01*
X28108D01*
Y92121D01*
X28119D01*
Y92132D01*
D02*
G37*
G36*
X28085Y92098D02*
X28073D01*
Y92086D01*
X28062D01*
Y92075D01*
X28096D01*
Y92086D01*
X28085D01*
Y92098D01*
D02*
G37*
G36*
X32380Y91395D02*
X32369D01*
Y91384D01*
X32380D01*
Y91395D01*
D02*
G37*
G36*
X31620Y91199D02*
X31609D01*
Y91188D01*
X31620D01*
Y91199D01*
D02*
G37*
G36*
X31436Y91153D02*
X31424D01*
Y91142D01*
X31436D01*
Y91153D01*
D02*
G37*
G36*
X31206Y91246D02*
X31194D01*
Y91234D01*
X31206D01*
Y91246D01*
D02*
G37*
G36*
X31183D02*
X31137D01*
Y91234D01*
X31183D01*
Y91246D01*
D02*
G37*
G36*
X130786Y83561D02*
X128191D01*
Y83507D01*
X127543D01*
Y83453D01*
X127002D01*
Y83398D01*
X126624D01*
Y83344D01*
X126245D01*
Y83290D01*
X125921D01*
Y83236D01*
X125596D01*
Y83182D01*
X125326D01*
Y83128D01*
X125110D01*
Y83074D01*
X124840D01*
Y83020D01*
X124623D01*
Y82966D01*
X124407D01*
Y82912D01*
X124191D01*
Y82858D01*
X123975D01*
Y82804D01*
X123812D01*
Y82750D01*
X123596D01*
Y82696D01*
X123434D01*
Y82642D01*
X123272D01*
Y82588D01*
X123056D01*
Y82534D01*
X122893D01*
Y82479D01*
X122731D01*
Y82425D01*
X122623D01*
Y82371D01*
X122461D01*
Y82317D01*
X122299D01*
Y82263D01*
X122136D01*
Y82209D01*
X122028D01*
Y82155D01*
X121866D01*
Y82101D01*
X121758D01*
Y82047D01*
X121596D01*
Y81993D01*
X121488D01*
Y81939D01*
X121326D01*
Y81885D01*
X121217D01*
Y81831D01*
X121109D01*
Y81777D01*
X120947D01*
Y81723D01*
X120839D01*
Y81669D01*
X120731D01*
Y81615D01*
X120623D01*
Y81560D01*
X120515D01*
Y81506D01*
X120406D01*
Y81452D01*
X120298D01*
Y81398D01*
X120190D01*
Y81344D01*
X120082D01*
Y81290D01*
X119974D01*
Y81236D01*
X119866D01*
Y81182D01*
X119758D01*
Y81128D01*
X119650D01*
Y81074D01*
X119542D01*
Y81020D01*
X119433D01*
Y80966D01*
X119325D01*
Y80912D01*
X119271D01*
Y80858D01*
X119163D01*
Y80804D01*
X119055D01*
Y80749D01*
X118947D01*
Y80695D01*
X118893D01*
Y80641D01*
X118785D01*
Y80587D01*
X118676D01*
Y80533D01*
X118623D01*
Y80479D01*
X118514D01*
Y80425D01*
X118460D01*
Y80371D01*
X118352D01*
Y80317D01*
X118244D01*
Y80263D01*
X118190D01*
Y80209D01*
X118082D01*
Y80155D01*
X118028D01*
Y80101D01*
X117920D01*
Y80047D01*
X117866D01*
Y79993D01*
X117757D01*
Y79939D01*
X117703D01*
Y79884D01*
X117595D01*
Y79830D01*
X117541D01*
Y79776D01*
X117487D01*
Y79722D01*
X117379D01*
Y79668D01*
X117325D01*
Y79614D01*
X117217D01*
Y79560D01*
X117163D01*
Y79506D01*
X117109D01*
Y79452D01*
X117001D01*
Y79398D01*
X116946D01*
Y79344D01*
X116893D01*
Y79290D01*
X116784D01*
Y79236D01*
X116730D01*
Y79182D01*
X116676D01*
Y79128D01*
X116568D01*
Y79074D01*
X116514D01*
Y79019D01*
X116460D01*
Y78965D01*
X116406D01*
Y78911D01*
X116298D01*
Y78857D01*
X116244D01*
Y78803D01*
X116190D01*
Y78749D01*
X116136D01*
Y78695D01*
X116082D01*
Y78641D01*
X115973D01*
Y78587D01*
X115919D01*
Y78533D01*
X115865D01*
Y78479D01*
X115811D01*
Y78425D01*
X115757D01*
Y78371D01*
X115703D01*
Y78317D01*
X115649D01*
Y78263D01*
X115541D01*
Y78209D01*
X115487D01*
Y78154D01*
X115433D01*
Y78100D01*
X115379D01*
Y78046D01*
X115325D01*
Y77992D01*
X115271D01*
Y77938D01*
X115217D01*
Y77884D01*
X115163D01*
Y77830D01*
X115108D01*
Y77776D01*
X115054D01*
Y77722D01*
X115000D01*
Y77668D01*
X114946D01*
Y77614D01*
X114892D01*
Y77560D01*
X114838D01*
Y77506D01*
X114784D01*
Y77452D01*
X114730D01*
Y77398D01*
X114676D01*
Y77344D01*
X114622D01*
Y77289D01*
X114568D01*
Y77235D01*
X114514D01*
Y77181D01*
X114460D01*
Y77127D01*
X114406D01*
Y77073D01*
X114352D01*
Y77019D01*
X114297D01*
Y76965D01*
X114243D01*
Y76911D01*
X114189D01*
Y76857D01*
X114135D01*
Y76803D01*
X114081D01*
Y76749D01*
X114027D01*
Y76695D01*
X113973D01*
Y76641D01*
X113919D01*
Y76587D01*
Y76533D01*
X113865D01*
Y76479D01*
X113811D01*
Y76424D01*
X113757D01*
Y76371D01*
X113703D01*
Y76316D01*
X113649D01*
Y76262D01*
X113595D01*
Y76208D01*
X113541D01*
Y76154D01*
Y76100D01*
X113487D01*
Y76046D01*
X113433D01*
Y75992D01*
X113378D01*
Y75938D01*
X113324D01*
Y75884D01*
Y75830D01*
X113270D01*
Y75776D01*
X113216D01*
Y75722D01*
X113162D01*
Y75668D01*
X113108D01*
Y75614D01*
Y75560D01*
X113054D01*
Y75505D01*
X113000D01*
Y75451D01*
X112946D01*
Y75397D01*
X112892D01*
Y75343D01*
Y75289D01*
X112838D01*
Y75235D01*
X112784D01*
Y75181D01*
X112730D01*
Y75127D01*
Y75073D01*
X112676D01*
Y75019D01*
X112622D01*
Y74965D01*
X112567D01*
Y74911D01*
Y74857D01*
X112513D01*
Y74803D01*
X112459D01*
Y74749D01*
Y74695D01*
X112405D01*
Y74641D01*
X112351D01*
Y74586D01*
X112297D01*
Y74532D01*
Y74478D01*
X112243D01*
Y74424D01*
X112189D01*
Y74370D01*
Y74316D01*
X112135D01*
Y74262D01*
X112081D01*
Y74208D01*
Y74154D01*
X112027D01*
Y74100D01*
X111973D01*
Y74046D01*
Y73992D01*
X111919D01*
Y73938D01*
X111865D01*
Y73884D01*
Y73830D01*
X111811D01*
Y73776D01*
Y73721D01*
X111757D01*
Y73667D01*
X111703D01*
Y73613D01*
Y73559D01*
X111648D01*
Y73505D01*
X111594D01*
Y73451D01*
Y73397D01*
X111540D01*
Y73343D01*
Y73289D01*
X111486D01*
Y73235D01*
Y73181D01*
X111432D01*
Y73127D01*
X111378D01*
Y73073D01*
Y73019D01*
X111324D01*
Y72965D01*
Y72910D01*
X111270D01*
Y72856D01*
Y72802D01*
X111216D01*
Y72748D01*
Y72694D01*
X111162D01*
Y72640D01*
X111108D01*
Y72586D01*
Y72532D01*
X111054D01*
Y72478D01*
Y72424D01*
X111000D01*
Y72370D01*
Y72316D01*
X110946D01*
Y72262D01*
Y72208D01*
X110892D01*
Y72154D01*
Y72100D01*
X110837D01*
Y72045D01*
Y71991D01*
X110784D01*
Y71937D01*
Y71883D01*
X110729D01*
Y71829D01*
Y71775D01*
X110675D01*
Y71721D01*
Y71667D01*
X110621D01*
Y71613D01*
Y71559D01*
X110567D01*
Y71505D01*
Y71451D01*
X110513D01*
Y71397D01*
Y71343D01*
X110459D01*
Y71289D01*
Y71235D01*
X110405D01*
Y71180D01*
Y71126D01*
Y71072D01*
X110351D01*
Y71018D01*
Y70964D01*
X110297D01*
Y70910D01*
Y70856D01*
X110243D01*
Y70802D01*
Y70748D01*
Y70694D01*
X110189D01*
Y70640D01*
Y70586D01*
X110135D01*
Y70532D01*
Y70478D01*
Y70424D01*
X110081D01*
Y70370D01*
Y70315D01*
X110027D01*
Y70261D01*
Y70207D01*
Y70153D01*
X109973D01*
Y70099D01*
Y70045D01*
X109918D01*
Y69991D01*
Y69937D01*
Y69883D01*
X109864D01*
Y69829D01*
Y69775D01*
Y69721D01*
X109810D01*
Y69667D01*
Y69613D01*
Y69559D01*
X109756D01*
Y69505D01*
Y69450D01*
Y69397D01*
X109702D01*
Y69342D01*
Y69288D01*
Y69234D01*
X109648D01*
Y69180D01*
Y69126D01*
Y69072D01*
X109594D01*
Y69018D01*
Y68964D01*
Y68910D01*
X109540D01*
Y68856D01*
Y68802D01*
Y68748D01*
X109486D01*
Y68694D01*
Y68640D01*
Y68585D01*
X109432D01*
Y68531D01*
Y68477D01*
Y68423D01*
Y68369D01*
X109378D01*
Y68315D01*
Y68261D01*
Y68207D01*
X109324D01*
Y68153D01*
Y68099D01*
Y68045D01*
Y67991D01*
X109270D01*
Y67937D01*
Y67883D01*
Y67829D01*
Y67775D01*
X109216D01*
Y67721D01*
Y67667D01*
Y67612D01*
Y67558D01*
X109162D01*
Y67504D01*
Y67450D01*
Y67396D01*
Y67342D01*
X109107D01*
Y67288D01*
Y67234D01*
Y67180D01*
Y67126D01*
Y67072D01*
X109054D01*
Y67018D01*
Y66964D01*
Y66910D01*
Y66856D01*
Y66802D01*
X108999D01*
Y66747D01*
Y66693D01*
Y66639D01*
Y66585D01*
Y66531D01*
X108945D01*
Y66477D01*
Y66423D01*
Y66369D01*
Y66315D01*
Y66261D01*
X108891D01*
Y66207D01*
Y66153D01*
Y66099D01*
Y66045D01*
Y65991D01*
Y65936D01*
X108837D01*
Y65882D01*
Y65828D01*
Y65774D01*
Y65720D01*
Y65666D01*
Y65612D01*
Y65558D01*
X108783D01*
Y65504D01*
Y65450D01*
Y65396D01*
Y65342D01*
Y65288D01*
Y65234D01*
Y65180D01*
Y65126D01*
X108729D01*
Y65071D01*
Y65017D01*
Y64963D01*
Y64909D01*
Y64855D01*
Y64801D01*
Y64747D01*
Y64693D01*
Y64639D01*
Y64585D01*
X108675D01*
Y64531D01*
X108729D01*
Y64477D01*
X108675D01*
Y64423D01*
Y64369D01*
Y64315D01*
Y64261D01*
Y64206D01*
Y64152D01*
Y64098D01*
Y64044D01*
Y63990D01*
Y63936D01*
Y63882D01*
X108621D01*
Y63828D01*
Y63774D01*
Y63720D01*
Y63666D01*
Y63612D01*
Y63558D01*
Y63504D01*
Y63450D01*
Y63396D01*
Y63341D01*
Y63287D01*
X109270D01*
Y63341D01*
Y63396D01*
Y63450D01*
Y63504D01*
Y63558D01*
Y63612D01*
X109324D01*
Y63666D01*
Y63720D01*
Y63774D01*
Y63828D01*
Y63882D01*
Y63936D01*
Y63990D01*
Y64044D01*
Y64098D01*
Y64152D01*
Y64206D01*
Y64261D01*
Y64315D01*
Y64369D01*
Y64423D01*
Y64477D01*
X109378D01*
Y64531D01*
Y64585D01*
Y64639D01*
Y64693D01*
Y64747D01*
Y64801D01*
Y64855D01*
Y64909D01*
Y64963D01*
Y65017D01*
X109432D01*
Y65071D01*
Y65126D01*
Y65180D01*
Y65234D01*
Y65288D01*
Y65342D01*
Y65396D01*
Y65450D01*
X109486D01*
Y65504D01*
Y65558D01*
Y65612D01*
Y65666D01*
Y65720D01*
Y65774D01*
Y65828D01*
X109540D01*
Y65882D01*
Y65936D01*
Y65991D01*
Y66045D01*
Y66099D01*
Y66153D01*
X109594D01*
Y66207D01*
Y66261D01*
Y66315D01*
Y66369D01*
Y66423D01*
X109648D01*
Y66477D01*
Y66531D01*
Y66585D01*
Y66639D01*
Y66693D01*
X109702D01*
Y66747D01*
Y66802D01*
Y66856D01*
Y66910D01*
Y66964D01*
X109756D01*
Y67018D01*
Y67072D01*
Y67126D01*
Y67180D01*
Y67234D01*
X109810D01*
Y67288D01*
Y67342D01*
Y67396D01*
Y67450D01*
X109864D01*
Y67504D01*
Y67558D01*
Y67612D01*
Y67667D01*
X109918D01*
Y67721D01*
Y67775D01*
Y67829D01*
Y67883D01*
X109973D01*
Y67937D01*
Y67991D01*
Y68045D01*
Y68099D01*
X110027D01*
Y68153D01*
Y68207D01*
Y68261D01*
X110081D01*
Y68315D01*
Y68369D01*
Y68423D01*
Y68477D01*
X110135D01*
Y68531D01*
Y68585D01*
Y68640D01*
X110189D01*
Y68694D01*
Y68748D01*
Y68802D01*
X110243D01*
Y68856D01*
Y68910D01*
Y68964D01*
X110297D01*
Y69018D01*
Y69072D01*
Y69126D01*
X110351D01*
Y69180D01*
Y69234D01*
Y69288D01*
X110405D01*
Y69342D01*
Y69397D01*
Y69450D01*
X110459D01*
Y69505D01*
Y69559D01*
Y69613D01*
X110513D01*
Y69667D01*
Y69721D01*
X110567D01*
Y69775D01*
Y69829D01*
Y69883D01*
X110621D01*
Y69937D01*
Y69991D01*
Y70045D01*
X110675D01*
Y70099D01*
Y70153D01*
X110729D01*
Y70207D01*
Y70261D01*
Y70315D01*
X110784D01*
Y70370D01*
Y70424D01*
X110837D01*
Y70478D01*
Y70532D01*
X110892D01*
Y70586D01*
Y70640D01*
Y70694D01*
X110946D01*
Y70748D01*
Y70802D01*
X111000D01*
Y70856D01*
Y70910D01*
X111054D01*
Y70964D01*
Y71018D01*
Y71072D01*
X111108D01*
Y71126D01*
Y71180D01*
X111162D01*
Y71235D01*
Y71289D01*
X111216D01*
Y71343D01*
Y71397D01*
X111270D01*
Y71451D01*
Y71505D01*
X111324D01*
Y71559D01*
Y71613D01*
X111378D01*
Y71667D01*
Y71721D01*
X111432D01*
Y71775D01*
Y71829D01*
X111486D01*
Y71883D01*
Y71937D01*
X111540D01*
Y71991D01*
Y72045D01*
X111594D01*
Y72100D01*
Y72154D01*
X111648D01*
Y72208D01*
Y72262D01*
X111703D01*
Y72316D01*
Y72370D01*
X111757D01*
Y72424D01*
X111811D01*
Y72478D01*
Y72532D01*
X111865D01*
Y72586D01*
Y72640D01*
X111919D01*
Y72694D01*
Y72748D01*
X111973D01*
Y72802D01*
X112027D01*
Y72856D01*
Y72910D01*
X112081D01*
Y72965D01*
Y73019D01*
X112135D01*
Y73073D01*
Y73127D01*
X112189D01*
Y73181D01*
X112243D01*
Y73235D01*
Y73289D01*
X112297D01*
Y73343D01*
X112351D01*
Y73397D01*
Y73451D01*
X112405D01*
Y73505D01*
Y73559D01*
X112459D01*
Y73613D01*
X112513D01*
Y73667D01*
Y73721D01*
X112567D01*
Y73776D01*
X112622D01*
Y73830D01*
Y73884D01*
X112676D01*
Y73938D01*
X112730D01*
Y73992D01*
Y74046D01*
X112784D01*
Y74100D01*
X112838D01*
Y74154D01*
Y74208D01*
X112892D01*
Y74262D01*
X112946D01*
Y74316D01*
Y74370D01*
X113000D01*
Y74424D01*
X113054D01*
Y74478D01*
X113108D01*
Y74532D01*
Y74586D01*
X113162D01*
Y74641D01*
X113216D01*
Y74695D01*
X113270D01*
Y74749D01*
Y74803D01*
X113324D01*
Y74857D01*
X113378D01*
Y74911D01*
X113433D01*
Y74965D01*
Y75019D01*
X113487D01*
Y75073D01*
X113541D01*
Y75127D01*
X113595D01*
Y75181D01*
Y75235D01*
X113649D01*
Y75289D01*
X113703D01*
Y75343D01*
X113757D01*
Y75397D01*
X113811D01*
Y75451D01*
Y75505D01*
X113865D01*
Y75560D01*
X113919D01*
Y75614D01*
X113973D01*
Y75668D01*
X114027D01*
Y75722D01*
X114081D01*
Y75776D01*
Y75830D01*
X114135D01*
Y75884D01*
X114189D01*
Y75938D01*
X114243D01*
Y75992D01*
X114297D01*
Y76046D01*
X114352D01*
Y76100D01*
X114406D01*
Y76154D01*
X114460D01*
Y76208D01*
Y76262D01*
X114514D01*
Y76316D01*
X114568D01*
Y76371D01*
X114622D01*
Y76424D01*
X114676D01*
Y76479D01*
X114730D01*
Y76533D01*
X114784D01*
Y76587D01*
X114838D01*
Y76641D01*
X114892D01*
Y76695D01*
X114946D01*
Y76749D01*
X115000D01*
Y76803D01*
X115054D01*
Y76857D01*
X115108D01*
Y76911D01*
X115163D01*
Y76965D01*
X115217D01*
Y77019D01*
X115271D01*
Y77073D01*
X115325D01*
Y77127D01*
X115379D01*
Y77181D01*
X115433D01*
Y77235D01*
X115487D01*
Y77289D01*
X115541D01*
Y77344D01*
X115595D01*
Y77398D01*
X115649D01*
Y77452D01*
X115703D01*
Y77506D01*
X115757D01*
Y77560D01*
X115811D01*
Y77614D01*
X115865D01*
Y77668D01*
X115919D01*
Y77722D01*
X116027D01*
Y77776D01*
X116082D01*
Y77830D01*
X116136D01*
Y77884D01*
X116190D01*
Y77938D01*
X116244D01*
Y77992D01*
X116298D01*
Y78046D01*
X116352D01*
Y78100D01*
X116460D01*
Y78154D01*
X116514D01*
Y78209D01*
X116568D01*
Y78263D01*
X116622D01*
Y78317D01*
X116676D01*
Y78371D01*
X116784D01*
Y78425D01*
X116838D01*
Y78479D01*
X116893D01*
Y78533D01*
X116946D01*
Y78587D01*
X117055D01*
Y78641D01*
X117109D01*
Y78695D01*
X117163D01*
Y78749D01*
X117271D01*
Y78803D01*
X117325D01*
Y78857D01*
X117379D01*
Y78911D01*
X117487D01*
Y78965D01*
X117541D01*
Y79019D01*
X117595D01*
Y79074D01*
X117703D01*
Y79128D01*
X117757D01*
Y79182D01*
X117812D01*
Y79236D01*
X117920D01*
Y79290D01*
X117974D01*
Y79344D01*
X118082D01*
Y79398D01*
X118136D01*
Y79452D01*
X118244D01*
Y79506D01*
X118298D01*
Y79560D01*
X118406D01*
Y79614D01*
X118460D01*
Y79668D01*
X118568D01*
Y79722D01*
X118623D01*
Y79776D01*
X118731D01*
Y79830D01*
X118839D01*
Y79884D01*
X118893D01*
Y79939D01*
X119001D01*
Y79993D01*
X119055D01*
Y80047D01*
X119163D01*
Y80101D01*
X119271D01*
Y80155D01*
X119325D01*
Y80209D01*
X119433D01*
Y80263D01*
X119542D01*
Y80317D01*
X119650D01*
Y80371D01*
X119758D01*
Y80425D01*
X119812D01*
Y80479D01*
X119920D01*
Y80533D01*
X120028D01*
Y80587D01*
X120136D01*
Y80641D01*
X120244D01*
Y80695D01*
X120352D01*
Y80749D01*
X120461D01*
Y80804D01*
X120569D01*
Y80858D01*
X120677D01*
Y80912D01*
X120785D01*
Y80966D01*
X120893D01*
Y81020D01*
X121001D01*
Y81074D01*
X121109D01*
Y81128D01*
X121272D01*
Y81182D01*
X121380D01*
Y81236D01*
X121488D01*
Y81290D01*
X121596D01*
Y81344D01*
X121758D01*
Y81398D01*
X121866D01*
Y81452D01*
X122028D01*
Y81506D01*
X122136D01*
Y81560D01*
X122299D01*
Y81615D01*
X122407D01*
Y81669D01*
X122569D01*
Y81723D01*
X122731D01*
Y81777D01*
X122893D01*
Y81831D01*
X123056D01*
Y81885D01*
X123218D01*
Y81939D01*
X123380D01*
Y81993D01*
X123542D01*
Y82047D01*
X123704D01*
Y82101D01*
X123921D01*
Y82155D01*
X124083D01*
Y82209D01*
X124299D01*
Y82263D01*
X124515D01*
Y82317D01*
X124732D01*
Y82371D01*
X124948D01*
Y82425D01*
X125164D01*
Y82479D01*
X125434D01*
Y82534D01*
X125705D01*
Y82588D01*
X126029D01*
Y82642D01*
X126353D01*
Y82696D01*
X126732D01*
Y82750D01*
X127164D01*
Y82804D01*
X127651D01*
Y82858D01*
X128462D01*
Y82912D01*
X130570D01*
Y82858D01*
X130678D01*
Y82912D01*
X130732D01*
Y82858D01*
X131327D01*
Y82804D01*
X131976D01*
Y82750D01*
X132300D01*
Y82696D01*
X132679D01*
Y82642D01*
X133003D01*
Y82588D01*
X133327D01*
Y82534D01*
X133598D01*
Y82479D01*
X133814D01*
Y82425D01*
X134084D01*
Y82371D01*
X134300D01*
Y82317D01*
X134517D01*
Y82263D01*
X134733D01*
Y82209D01*
X134949D01*
Y82155D01*
X135111D01*
Y82101D01*
X135328D01*
Y82047D01*
X135490D01*
Y81993D01*
X135652D01*
Y81939D01*
X135814D01*
Y81885D01*
X135976D01*
Y81831D01*
X136139D01*
Y81777D01*
X136301D01*
Y81723D01*
X136463D01*
Y81669D01*
X136571D01*
Y81615D01*
X136733D01*
Y81560D01*
X136895D01*
Y81506D01*
X137004D01*
Y81452D01*
X137166D01*
Y81398D01*
X137274D01*
Y81344D01*
X137382D01*
Y81290D01*
X137544D01*
Y81236D01*
X137652D01*
Y81182D01*
X137814D01*
Y81128D01*
X137923D01*
Y81074D01*
X138031D01*
Y81020D01*
X138139D01*
Y80966D01*
X138247D01*
Y80912D01*
X138355D01*
Y80858D01*
X138463D01*
Y80804D01*
X138571D01*
Y80749D01*
X138680D01*
Y80695D01*
X138788D01*
Y80641D01*
X138896D01*
Y80587D01*
X139004D01*
Y80533D01*
X139112D01*
Y80479D01*
X139220D01*
Y80425D01*
X139274D01*
Y80371D01*
X139382D01*
Y80317D01*
X139490D01*
Y80263D01*
X139599D01*
Y80209D01*
X139653D01*
Y80155D01*
X139761D01*
Y80101D01*
X139869D01*
Y80047D01*
X139923D01*
Y79993D01*
X140031D01*
Y79939D01*
X140139D01*
Y79884D01*
X140193D01*
Y79830D01*
X140301D01*
Y79776D01*
X140410D01*
Y79722D01*
X140463D01*
Y79668D01*
X140572D01*
Y79614D01*
X140626D01*
Y79560D01*
X140734D01*
Y79506D01*
X140788D01*
Y79452D01*
X140896D01*
Y79398D01*
X140950D01*
Y79344D01*
X141058D01*
Y79290D01*
X141112D01*
Y79236D01*
X141166D01*
Y79182D01*
X141274D01*
Y79128D01*
X141329D01*
Y79074D01*
X141437D01*
Y79019D01*
X141491D01*
Y78965D01*
X141545D01*
Y78911D01*
X141653D01*
Y78857D01*
X141707D01*
Y78803D01*
X141761D01*
Y78749D01*
X141869D01*
Y78695D01*
X141923D01*
Y78641D01*
X141977D01*
Y78587D01*
X142031D01*
Y78533D01*
X142139D01*
Y78479D01*
X142193D01*
Y78425D01*
X142248D01*
Y78371D01*
X142302D01*
Y78317D01*
X142410D01*
Y78263D01*
X142464D01*
Y78209D01*
X142518D01*
Y78154D01*
X142572D01*
Y78100D01*
X142626D01*
Y78046D01*
X142734D01*
Y77992D01*
X142788D01*
Y77938D01*
X142842D01*
Y77884D01*
X142896D01*
Y77830D01*
X142950D01*
Y77776D01*
X143004D01*
Y77722D01*
X143059D01*
Y77668D01*
X143167D01*
Y77614D01*
X143221D01*
Y77560D01*
X143275D01*
Y77506D01*
X143329D01*
Y77452D01*
X143383D01*
Y77398D01*
X143437D01*
Y77344D01*
X143491D01*
Y77289D01*
X143545D01*
Y77235D01*
X143599D01*
Y77181D01*
X143653D01*
Y77127D01*
X143707D01*
Y77073D01*
X143761D01*
Y77019D01*
X143815D01*
Y76965D01*
X143869D01*
Y76911D01*
X143923D01*
Y76857D01*
X143977D01*
Y76803D01*
X144032D01*
Y76749D01*
X144086D01*
Y76695D01*
X144140D01*
Y76641D01*
X144194D01*
Y76587D01*
X144248D01*
Y76533D01*
X144302D01*
Y76479D01*
X144356D01*
Y76424D01*
X144410D01*
Y76371D01*
X144464D01*
Y76316D01*
X144518D01*
Y76262D01*
Y76208D01*
X144572D01*
Y76154D01*
X144626D01*
Y76100D01*
X145491D01*
Y76154D01*
X145437D01*
Y76208D01*
Y76262D01*
X145383D01*
Y76316D01*
X145329D01*
Y76371D01*
X145275D01*
Y76424D01*
X145221D01*
Y76479D01*
X145167D01*
Y76533D01*
X145113D01*
Y76587D01*
X145059D01*
Y76641D01*
Y76695D01*
X145005D01*
Y76749D01*
X144951D01*
Y76803D01*
X144897D01*
Y76857D01*
X144843D01*
Y76911D01*
X144789D01*
Y76965D01*
X144734D01*
Y77019D01*
X144680D01*
Y77073D01*
X144626D01*
Y77127D01*
X144572D01*
Y77181D01*
X144518D01*
Y77235D01*
X144464D01*
Y77289D01*
X144410D01*
Y77344D01*
X144356D01*
Y77398D01*
X144302D01*
Y77452D01*
X144248D01*
Y77506D01*
X144194D01*
Y77560D01*
X144140D01*
Y77614D01*
X144086D01*
Y77668D01*
X144032D01*
Y77722D01*
X143977D01*
Y77776D01*
X143923D01*
Y77830D01*
X143869D01*
Y77884D01*
X143815D01*
Y77938D01*
X143761D01*
Y77992D01*
X143707D01*
Y78046D01*
X143653D01*
Y78100D01*
X143599D01*
Y78154D01*
X143545D01*
Y78209D01*
X143437D01*
Y78263D01*
X143383D01*
Y78317D01*
X143329D01*
Y78371D01*
X143275D01*
Y78425D01*
X143221D01*
Y78479D01*
X143167D01*
Y78533D01*
X143113D01*
Y78587D01*
X143004D01*
Y78641D01*
X142950D01*
Y78695D01*
X142896D01*
Y78749D01*
X142842D01*
Y78803D01*
X142788D01*
Y78857D01*
X142680D01*
Y78911D01*
X142626D01*
Y78965D01*
X142572D01*
Y79019D01*
X142518D01*
Y79074D01*
X142410D01*
Y79128D01*
X142356D01*
Y79182D01*
X142302D01*
Y79236D01*
X142248D01*
Y79290D01*
X142139D01*
Y79344D01*
X142085D01*
Y79398D01*
X142031D01*
Y79452D01*
X141923D01*
Y79506D01*
X141869D01*
Y79560D01*
X141815D01*
Y79614D01*
X141707D01*
Y79668D01*
X141653D01*
Y79722D01*
X141545D01*
Y79776D01*
X141491D01*
Y79830D01*
X141383D01*
Y79884D01*
X141329D01*
Y79939D01*
X141274D01*
Y79993D01*
X141166D01*
Y80047D01*
X141112D01*
Y80101D01*
X141004D01*
Y80155D01*
X140950D01*
Y80209D01*
X140842D01*
Y80263D01*
X140734D01*
Y80317D01*
X140680D01*
Y80371D01*
X140572D01*
Y80425D01*
X140518D01*
Y80479D01*
X140410D01*
Y80533D01*
X140301D01*
Y80587D01*
X140247D01*
Y80641D01*
X140139D01*
Y80695D01*
X140031D01*
Y80749D01*
X139977D01*
Y80804D01*
X139869D01*
Y80858D01*
X139761D01*
Y80912D01*
X139653D01*
Y80966D01*
X139599D01*
Y81020D01*
X139490D01*
Y81074D01*
X139382D01*
Y81128D01*
X139274D01*
Y81182D01*
X139166D01*
Y81236D01*
X139058D01*
Y81290D01*
X138950D01*
Y81344D01*
X138842D01*
Y81398D01*
X138733D01*
Y81452D01*
X138625D01*
Y81506D01*
X138517D01*
Y81560D01*
X138409D01*
Y81615D01*
X138301D01*
Y81669D01*
X138193D01*
Y81723D01*
X138085D01*
Y81777D01*
X137923D01*
Y81831D01*
X137814D01*
Y81885D01*
X137706D01*
Y81939D01*
X137544D01*
Y81993D01*
X137436D01*
Y82047D01*
X137274D01*
Y82101D01*
X137166D01*
Y82155D01*
X137004D01*
Y82209D01*
X136895D01*
Y82263D01*
X136733D01*
Y82317D01*
X136571D01*
Y82371D01*
X136409D01*
Y82425D01*
X136247D01*
Y82479D01*
X136084D01*
Y82534D01*
X135922D01*
Y82588D01*
X135760D01*
Y82642D01*
X135598D01*
Y82696D01*
X135436D01*
Y82750D01*
X135220D01*
Y82804D01*
X135057D01*
Y82858D01*
X134841D01*
Y82912D01*
X134625D01*
Y82966D01*
X134409D01*
Y83020D01*
X134138D01*
Y83074D01*
X133922D01*
Y83128D01*
X133706D01*
Y83182D01*
X133381D01*
Y83236D01*
X133111D01*
Y83290D01*
X132787D01*
Y83344D01*
X132408D01*
Y83398D01*
X131976D01*
Y83453D01*
X131489D01*
Y83507D01*
X130786D01*
Y83561D01*
D02*
G37*
G36*
X145870Y75019D02*
X142842D01*
Y74965D01*
X142734D01*
Y74911D01*
X142680D01*
Y74857D01*
X142626D01*
Y74803D01*
X142572D01*
Y74749D01*
X142518D01*
Y74695D01*
Y74641D01*
X142464D01*
Y74586D01*
Y74532D01*
X142410D01*
Y74478D01*
X142356D01*
Y74424D01*
Y74370D01*
X142302D01*
Y74316D01*
Y74262D01*
X142248D01*
Y74208D01*
Y74154D01*
X142193D01*
Y74100D01*
X142139D01*
Y74046D01*
Y73992D01*
X142085D01*
Y73938D01*
Y73884D01*
X142031D01*
Y73830D01*
X141977D01*
Y73776D01*
Y73721D01*
X141923D01*
Y73667D01*
Y73613D01*
X141869D01*
Y73559D01*
X141815D01*
Y73505D01*
Y73451D01*
X141761D01*
Y73397D01*
Y73343D01*
X141707D01*
Y73289D01*
X141653D01*
Y73235D01*
Y73181D01*
X141599D01*
Y73127D01*
Y73073D01*
X141545D01*
Y73019D01*
Y72965D01*
X141491D01*
Y72910D01*
X141437D01*
Y72856D01*
Y72802D01*
X141383D01*
Y72748D01*
Y72694D01*
X141329D01*
Y72640D01*
X141274D01*
Y72586D01*
Y72532D01*
X141220D01*
Y72478D01*
Y72424D01*
X141166D01*
Y72370D01*
X141112D01*
Y72316D01*
Y72262D01*
X141058D01*
Y72208D01*
Y72154D01*
X141004D01*
Y72100D01*
Y72045D01*
X140950D01*
Y71991D01*
X140896D01*
Y71937D01*
Y71883D01*
X140842D01*
Y71829D01*
Y71775D01*
X140788D01*
Y71721D01*
X140734D01*
Y71667D01*
Y71613D01*
X140680D01*
Y71559D01*
Y71505D01*
X138625D01*
Y71559D01*
Y71613D01*
Y71667D01*
Y71721D01*
Y71775D01*
X138571D01*
Y71829D01*
X138625D01*
Y71883D01*
Y71937D01*
Y71991D01*
Y72045D01*
Y72100D01*
Y72154D01*
Y72208D01*
Y72262D01*
Y72316D01*
Y72370D01*
Y72424D01*
Y72478D01*
Y72532D01*
Y72586D01*
Y72640D01*
Y72694D01*
Y72748D01*
Y72802D01*
Y72856D01*
Y72910D01*
Y72965D01*
Y73019D01*
Y73073D01*
Y73127D01*
Y73181D01*
Y73235D01*
Y73289D01*
Y73343D01*
Y73397D01*
Y73451D01*
Y73505D01*
Y73559D01*
Y73613D01*
Y73667D01*
Y73721D01*
Y73776D01*
Y73830D01*
Y73884D01*
Y73938D01*
Y73992D01*
Y74046D01*
Y74100D01*
Y74154D01*
Y74208D01*
Y74262D01*
Y74316D01*
Y74370D01*
Y74424D01*
Y74478D01*
Y74532D01*
Y74586D01*
Y74641D01*
Y74695D01*
Y74749D01*
X138571D01*
Y74803D01*
Y74857D01*
Y74911D01*
X138517D01*
Y74965D01*
X138463D01*
Y75019D01*
X135814D01*
Y74965D01*
X135706D01*
Y74911D01*
X135652D01*
Y74857D01*
Y74803D01*
Y74749D01*
X135598D01*
Y74695D01*
X135652D01*
Y74641D01*
X135598D01*
Y74586D01*
Y74532D01*
Y74478D01*
Y74424D01*
Y74370D01*
Y74316D01*
Y74262D01*
Y74208D01*
Y74154D01*
Y74100D01*
Y74046D01*
Y73992D01*
Y73938D01*
Y73884D01*
Y73830D01*
Y73776D01*
Y73721D01*
Y73667D01*
Y73613D01*
Y73559D01*
Y73505D01*
Y73451D01*
Y73397D01*
Y73343D01*
Y73289D01*
Y73235D01*
Y73181D01*
Y73127D01*
Y73073D01*
Y73019D01*
Y72965D01*
Y72910D01*
Y72856D01*
Y72802D01*
Y72748D01*
Y72694D01*
Y72640D01*
Y72586D01*
Y72532D01*
Y72478D01*
Y72424D01*
Y72370D01*
Y72316D01*
Y72262D01*
Y72208D01*
Y72154D01*
Y72100D01*
Y72045D01*
Y71991D01*
Y71937D01*
Y71883D01*
Y71829D01*
Y71775D01*
Y71721D01*
Y71667D01*
Y71613D01*
Y71559D01*
Y71505D01*
Y71451D01*
Y71397D01*
Y71343D01*
Y71289D01*
Y71235D01*
Y71180D01*
Y71126D01*
Y71072D01*
Y71018D01*
Y70964D01*
Y70910D01*
Y70856D01*
Y70802D01*
Y70748D01*
Y70694D01*
Y70640D01*
Y70586D01*
Y70532D01*
Y70478D01*
Y70424D01*
Y70370D01*
Y70315D01*
Y70261D01*
Y70207D01*
Y70153D01*
Y70099D01*
Y70045D01*
Y69991D01*
Y69937D01*
Y69883D01*
Y69829D01*
Y69775D01*
Y69721D01*
Y69667D01*
Y69613D01*
Y69559D01*
Y69505D01*
Y69450D01*
Y69397D01*
Y69342D01*
Y69288D01*
Y69234D01*
Y69180D01*
Y69126D01*
Y69072D01*
Y69018D01*
Y68964D01*
Y68910D01*
Y68856D01*
Y68802D01*
Y68748D01*
Y68694D01*
Y68640D01*
Y68585D01*
Y68531D01*
Y68477D01*
Y68423D01*
Y68369D01*
Y68315D01*
Y68261D01*
Y68207D01*
Y68153D01*
Y68099D01*
Y68045D01*
Y67991D01*
Y67937D01*
Y67883D01*
Y67829D01*
Y67775D01*
Y67721D01*
Y67667D01*
Y67612D01*
Y67558D01*
Y67504D01*
Y67450D01*
Y67396D01*
Y67342D01*
Y67288D01*
Y67234D01*
Y67180D01*
Y67126D01*
Y67072D01*
Y67018D01*
Y66964D01*
Y66910D01*
Y66856D01*
Y66802D01*
Y66747D01*
Y66693D01*
Y66639D01*
Y66585D01*
Y66531D01*
Y66477D01*
Y66423D01*
Y66369D01*
Y66315D01*
Y66261D01*
Y66207D01*
Y66153D01*
Y66099D01*
Y66045D01*
Y65991D01*
Y65936D01*
Y65882D01*
Y65828D01*
Y65774D01*
Y65720D01*
Y65666D01*
Y65612D01*
Y65558D01*
Y65504D01*
Y65450D01*
Y65396D01*
Y65342D01*
Y65288D01*
Y65234D01*
Y65180D01*
Y65126D01*
Y65071D01*
Y65017D01*
Y64963D01*
Y64909D01*
Y64855D01*
Y64801D01*
Y64747D01*
Y64693D01*
Y64639D01*
Y64585D01*
Y64531D01*
Y64477D01*
Y64423D01*
Y64369D01*
Y64315D01*
Y64261D01*
Y64206D01*
Y64152D01*
Y64098D01*
Y64044D01*
Y63990D01*
Y63936D01*
Y63882D01*
Y63828D01*
Y63774D01*
Y63720D01*
Y63666D01*
Y63612D01*
Y63558D01*
X135652D01*
Y63504D01*
Y63450D01*
Y63396D01*
X135706D01*
Y63341D01*
X135760D01*
Y63287D01*
X135868D01*
Y63233D01*
X143329D01*
Y63287D01*
X143599D01*
Y63341D01*
X143761D01*
Y63396D01*
X143869D01*
Y63450D01*
X143923D01*
Y63504D01*
X143977D01*
Y63558D01*
X144032D01*
Y63612D01*
X144086D01*
Y63666D01*
X144140D01*
Y63720D01*
X144194D01*
Y63774D01*
X144248D01*
Y63828D01*
X144302D01*
Y63882D01*
X144356D01*
Y63936D01*
X144410D01*
Y63990D01*
X144464D01*
Y64044D01*
X144518D01*
Y64098D01*
X144572D01*
Y64152D01*
X144626D01*
Y64206D01*
X144680D01*
Y64261D01*
X144734D01*
Y64315D01*
X144789D01*
Y64369D01*
X144843D01*
Y64423D01*
X144897D01*
Y64477D01*
X144951D01*
Y64531D01*
X145005D01*
Y64585D01*
X145059D01*
Y64639D01*
X145113D01*
Y64693D01*
X145167D01*
Y64747D01*
X145221D01*
Y64801D01*
X145275D01*
Y64855D01*
X145329D01*
Y64909D01*
X145383D01*
Y64963D01*
Y65017D01*
X145437D01*
Y65071D01*
Y65126D01*
Y65180D01*
X145491D01*
Y65234D01*
Y65288D01*
Y65342D01*
Y65396D01*
Y65450D01*
Y65504D01*
Y65558D01*
Y65612D01*
Y65666D01*
Y65720D01*
Y65774D01*
Y65828D01*
Y65882D01*
Y65936D01*
Y65991D01*
Y66045D01*
Y66099D01*
Y66153D01*
Y66207D01*
Y66261D01*
Y66315D01*
Y66369D01*
Y66423D01*
Y66477D01*
Y66531D01*
Y66585D01*
Y66639D01*
Y66693D01*
Y66747D01*
Y66802D01*
Y66856D01*
Y66910D01*
Y66964D01*
Y67018D01*
Y67072D01*
Y67126D01*
Y67180D01*
Y67234D01*
Y67288D01*
Y67342D01*
Y67396D01*
Y67450D01*
Y67504D01*
Y67558D01*
Y67612D01*
Y67667D01*
Y67721D01*
Y67775D01*
Y67829D01*
Y67883D01*
Y67937D01*
Y67991D01*
Y68045D01*
Y68099D01*
Y68153D01*
Y68207D01*
Y68261D01*
Y68315D01*
Y68369D01*
Y68423D01*
Y68477D01*
Y68531D01*
Y68585D01*
Y68640D01*
Y68694D01*
Y68748D01*
Y68802D01*
Y68856D01*
Y68910D01*
Y68964D01*
Y69018D01*
Y69072D01*
Y69126D01*
Y69180D01*
Y69234D01*
Y69288D01*
Y69342D01*
Y69397D01*
Y69450D01*
X145437D01*
Y69505D01*
Y69559D01*
X145383D01*
Y69613D01*
Y69667D01*
X145329D01*
Y69721D01*
X145275D01*
Y69775D01*
X145221D01*
Y69829D01*
X145167D01*
Y69883D01*
X145113D01*
Y69937D01*
X145059D01*
Y69991D01*
Y70045D01*
X145005D01*
Y70099D01*
X144951D01*
Y70153D01*
X144897D01*
Y70207D01*
X144843D01*
Y70261D01*
X144789D01*
Y70315D01*
X144734D01*
Y70370D01*
X144680D01*
Y70424D01*
X144626D01*
Y70478D01*
X144572D01*
Y70532D01*
X144518D01*
Y70586D01*
X144464D01*
Y70640D01*
X144410D01*
Y70694D01*
X144356D01*
Y70748D01*
X144302D01*
Y70802D01*
X144248D01*
Y70856D01*
X144194D01*
Y70910D01*
X144140D01*
Y70964D01*
X144086D01*
Y71018D01*
X144032D01*
Y71072D01*
X143977D01*
Y71126D01*
X143923D01*
Y71180D01*
X143869D01*
Y71235D01*
X143815D01*
Y71289D01*
Y71343D01*
X143869D01*
Y71397D01*
X143923D01*
Y71451D01*
Y71505D01*
X143977D01*
Y71559D01*
Y71613D01*
X144032D01*
Y71667D01*
X144086D01*
Y71721D01*
Y71775D01*
X144140D01*
Y71829D01*
Y71883D01*
X144194D01*
Y71937D01*
Y71991D01*
X144248D01*
Y72045D01*
X144302D01*
Y72100D01*
Y72154D01*
X144356D01*
Y72208D01*
Y72262D01*
X144410D01*
Y72316D01*
X144464D01*
Y72370D01*
Y72424D01*
X144518D01*
Y72478D01*
Y72532D01*
X144572D01*
Y72586D01*
X144626D01*
Y72640D01*
Y72694D01*
X144680D01*
Y72748D01*
Y72802D01*
X144734D01*
Y72856D01*
X144789D01*
Y72910D01*
Y72965D01*
X144843D01*
Y73019D01*
Y73073D01*
X144897D01*
Y73127D01*
X144951D01*
Y73181D01*
Y73235D01*
X145005D01*
Y73289D01*
Y73343D01*
X145059D01*
Y73397D01*
X145113D01*
Y73451D01*
Y73505D01*
X145167D01*
Y73559D01*
Y73613D01*
X145221D01*
Y73667D01*
X145275D01*
Y73721D01*
Y73776D01*
X145329D01*
Y73830D01*
Y73884D01*
X145383D01*
Y73938D01*
X145437D01*
Y73992D01*
Y74046D01*
X145491D01*
Y74100D01*
Y74154D01*
X145545D01*
Y74208D01*
X145599D01*
Y74262D01*
Y74316D01*
X145653D01*
Y74370D01*
Y74424D01*
X145707D01*
Y74478D01*
X145762D01*
Y74532D01*
Y74586D01*
X145816D01*
Y74641D01*
Y74695D01*
X145870D01*
Y74749D01*
X145924D01*
Y74803D01*
Y74857D01*
Y74911D01*
Y74965D01*
X145870D01*
Y75019D01*
D02*
G37*
G36*
X134246D02*
X131705D01*
Y74965D01*
X131597D01*
Y74911D01*
X131543D01*
Y74857D01*
X131489D01*
Y74803D01*
Y74749D01*
Y74695D01*
Y74641D01*
Y74586D01*
Y74532D01*
Y74478D01*
Y74424D01*
Y74370D01*
Y74316D01*
Y74262D01*
Y74208D01*
Y74154D01*
Y74100D01*
Y74046D01*
Y73992D01*
Y73938D01*
Y73884D01*
Y73830D01*
Y73776D01*
Y73721D01*
Y73667D01*
Y73613D01*
Y73559D01*
Y73505D01*
Y73451D01*
Y73397D01*
Y73343D01*
Y73289D01*
Y73235D01*
Y73181D01*
Y73127D01*
Y73073D01*
Y73019D01*
Y72965D01*
Y72910D01*
Y72856D01*
Y72802D01*
Y72748D01*
Y72694D01*
Y72640D01*
Y72586D01*
Y72532D01*
Y72478D01*
Y72424D01*
Y72370D01*
Y72316D01*
Y72262D01*
Y72208D01*
Y72154D01*
Y72100D01*
Y72045D01*
Y71991D01*
Y71937D01*
Y71883D01*
Y71829D01*
Y71775D01*
Y71721D01*
Y71667D01*
Y71613D01*
Y71559D01*
X131435D01*
Y71505D01*
Y71451D01*
X131327D01*
Y71397D01*
X127705D01*
Y71451D01*
X127597D01*
Y71505D01*
Y71559D01*
X127543D01*
Y71613D01*
Y71667D01*
Y71721D01*
Y71775D01*
Y71829D01*
Y71883D01*
Y71937D01*
Y71991D01*
Y72045D01*
Y72100D01*
Y72154D01*
Y72208D01*
Y72262D01*
Y72316D01*
Y72370D01*
Y72424D01*
Y72478D01*
Y72532D01*
Y72586D01*
Y72640D01*
Y72694D01*
Y72748D01*
Y72802D01*
Y72856D01*
Y72910D01*
Y72965D01*
Y73019D01*
Y73073D01*
Y73127D01*
Y73181D01*
Y73235D01*
Y73289D01*
Y73343D01*
Y73397D01*
Y73451D01*
Y73505D01*
Y73559D01*
Y73613D01*
Y73667D01*
Y73721D01*
Y73776D01*
Y73830D01*
Y73884D01*
Y73938D01*
Y73992D01*
Y74046D01*
Y74100D01*
Y74154D01*
Y74208D01*
Y74262D01*
Y74316D01*
Y74370D01*
Y74424D01*
Y74478D01*
Y74532D01*
Y74586D01*
Y74641D01*
Y74695D01*
Y74749D01*
Y74803D01*
X127489D01*
Y74857D01*
Y74911D01*
X127435D01*
Y74965D01*
X127326D01*
Y75019D01*
X124785D01*
Y74965D01*
X124677D01*
Y74911D01*
X124623D01*
Y74857D01*
X124569D01*
Y74803D01*
Y74749D01*
Y74695D01*
Y74641D01*
Y74586D01*
Y74532D01*
Y74478D01*
Y74424D01*
Y74370D01*
Y74316D01*
Y74262D01*
Y74208D01*
Y74154D01*
Y74100D01*
Y74046D01*
Y73992D01*
Y73938D01*
Y73884D01*
Y73830D01*
Y73776D01*
Y73721D01*
Y73667D01*
Y73613D01*
Y73559D01*
Y73505D01*
Y73451D01*
Y73397D01*
Y73343D01*
Y73289D01*
Y73235D01*
Y73181D01*
Y73127D01*
Y73073D01*
Y73019D01*
Y72965D01*
Y72910D01*
Y72856D01*
Y72802D01*
Y72748D01*
Y72694D01*
Y72640D01*
Y72586D01*
Y72532D01*
Y72478D01*
Y72424D01*
Y72370D01*
Y72316D01*
Y72262D01*
Y72208D01*
Y72154D01*
Y72100D01*
Y72045D01*
Y71991D01*
Y71937D01*
Y71883D01*
Y71829D01*
Y71775D01*
Y71721D01*
Y71667D01*
Y71613D01*
Y71559D01*
Y71505D01*
Y71451D01*
Y71397D01*
Y71343D01*
Y71289D01*
Y71235D01*
Y71180D01*
Y71126D01*
Y71072D01*
Y71018D01*
Y70964D01*
Y70910D01*
Y70856D01*
Y70802D01*
Y70748D01*
Y70694D01*
Y70640D01*
Y70586D01*
Y70532D01*
X124623D01*
Y70478D01*
X124677D01*
Y70424D01*
X124732D01*
Y70370D01*
X124785D01*
Y70315D01*
X124840D01*
Y70261D01*
X124894D01*
Y70207D01*
X125002D01*
Y70153D01*
X125056D01*
Y70099D01*
X125110D01*
Y70045D01*
X125164D01*
Y69991D01*
X125218D01*
Y69937D01*
X125272D01*
Y69883D01*
X125326D01*
Y69829D01*
X125380D01*
Y69775D01*
X125434D01*
Y69721D01*
X125488D01*
Y69667D01*
X125542D01*
Y69613D01*
X125596D01*
Y69559D01*
X125651D01*
Y69505D01*
X125705D01*
Y69450D01*
X125759D01*
Y69397D01*
X125813D01*
Y69342D01*
X125867D01*
Y69288D01*
X125921D01*
Y69234D01*
X125975D01*
Y69180D01*
X126029D01*
Y69126D01*
X126083D01*
Y69072D01*
X126137D01*
Y69018D01*
X126191D01*
Y68964D01*
X126245D01*
Y68910D01*
X126299D01*
Y68856D01*
X126353D01*
Y68802D01*
X126407D01*
Y68748D01*
X126462D01*
Y68694D01*
X126515D01*
Y68640D01*
X126570D01*
Y68585D01*
X126624D01*
Y68531D01*
X126678D01*
Y68477D01*
X126732D01*
Y68423D01*
X126786D01*
Y68369D01*
X126840D01*
Y68315D01*
X126894D01*
Y68261D01*
X126948D01*
Y68207D01*
X127002D01*
Y68153D01*
X127056D01*
Y68099D01*
X127110D01*
Y68045D01*
X127164D01*
Y67991D01*
X127218D01*
Y67937D01*
X127272D01*
Y67883D01*
X127326D01*
Y67829D01*
X127381D01*
Y67775D01*
X127435D01*
Y67721D01*
X127489D01*
Y67667D01*
X127543D01*
Y67721D01*
Y67775D01*
Y67829D01*
Y67883D01*
Y67937D01*
Y67991D01*
Y68045D01*
Y68099D01*
Y68153D01*
Y68207D01*
Y68261D01*
Y68315D01*
Y68369D01*
Y68423D01*
Y68477D01*
Y68531D01*
Y68585D01*
Y68640D01*
Y68694D01*
Y68748D01*
Y68802D01*
Y68856D01*
X131489D01*
Y68802D01*
Y68748D01*
Y68694D01*
Y68640D01*
Y68585D01*
Y68531D01*
Y68477D01*
Y68423D01*
Y68369D01*
Y68315D01*
Y68261D01*
Y68207D01*
Y68153D01*
Y68099D01*
Y68045D01*
Y67991D01*
Y67937D01*
Y67883D01*
Y67829D01*
Y67775D01*
Y67721D01*
Y67667D01*
Y67612D01*
Y67558D01*
Y67504D01*
Y67450D01*
Y67396D01*
Y67342D01*
Y67288D01*
Y67234D01*
Y67180D01*
Y67126D01*
Y67072D01*
Y67018D01*
Y66964D01*
Y66910D01*
Y66856D01*
Y66802D01*
Y66747D01*
Y66693D01*
Y66639D01*
Y66585D01*
Y66531D01*
Y66477D01*
Y66423D01*
Y66369D01*
Y66315D01*
Y66261D01*
Y66207D01*
Y66153D01*
Y66099D01*
Y66045D01*
Y65991D01*
Y65936D01*
Y65882D01*
X129056D01*
Y65828D01*
X129111D01*
Y65774D01*
X129165D01*
Y65720D01*
X129219D01*
Y65666D01*
X129273D01*
Y65612D01*
X129327D01*
Y65558D01*
X129381D01*
Y65504D01*
X129435D01*
Y65450D01*
X129489D01*
Y65396D01*
X129543D01*
Y65342D01*
X129597D01*
Y65288D01*
X129651D01*
Y65234D01*
X129705D01*
Y65180D01*
X129759D01*
Y65126D01*
X129813D01*
Y65071D01*
X129867D01*
Y65017D01*
X129921D01*
Y64963D01*
X129975D01*
Y64909D01*
X130029D01*
Y64855D01*
X130084D01*
Y64801D01*
X130138D01*
Y64747D01*
X130192D01*
Y64693D01*
X130246D01*
Y64639D01*
X130300D01*
Y64585D01*
X130354D01*
Y64531D01*
X130408D01*
Y64477D01*
X130462D01*
Y64423D01*
X130516D01*
Y64369D01*
X130570D01*
Y64315D01*
X130624D01*
Y64261D01*
X130678D01*
Y64206D01*
X130732D01*
Y64152D01*
X130786D01*
Y64098D01*
X130841D01*
Y64044D01*
X130894D01*
Y63990D01*
X130949D01*
Y63936D01*
X131003D01*
Y63882D01*
X131057D01*
Y63828D01*
X131111D01*
Y63774D01*
X131165D01*
Y63720D01*
X131219D01*
Y63666D01*
X131273D01*
Y63612D01*
X131327D01*
Y63558D01*
X131381D01*
Y63504D01*
X131435D01*
Y63450D01*
X131489D01*
Y63396D01*
X131543D01*
Y63341D01*
X131597D01*
Y63287D01*
X131651D01*
Y63233D01*
X132408D01*
Y63287D01*
X132624D01*
Y63341D01*
X132733D01*
Y63396D01*
X132841D01*
Y63450D01*
X132895D01*
Y63504D01*
X132949D01*
Y63558D01*
X133003D01*
Y63612D01*
X133057D01*
Y63666D01*
X133111D01*
Y63720D01*
X133165D01*
Y63774D01*
X133219D01*
Y63828D01*
X133273D01*
Y63882D01*
X133327D01*
Y63936D01*
X133381D01*
Y63990D01*
X133435D01*
Y64044D01*
X133490D01*
Y64098D01*
X133544D01*
Y64152D01*
X133598D01*
Y64206D01*
X133652D01*
Y64261D01*
X133706D01*
Y64315D01*
X133760D01*
Y64369D01*
X133814D01*
Y64423D01*
X133868D01*
Y64477D01*
X133922D01*
Y64531D01*
X133976D01*
Y64585D01*
X134030D01*
Y64639D01*
X134084D01*
Y64693D01*
X134138D01*
Y64747D01*
X134192D01*
Y64801D01*
X134246D01*
Y64855D01*
X134300D01*
Y64909D01*
X134354D01*
Y64963D01*
Y65017D01*
Y65071D01*
X134409D01*
Y65126D01*
Y65180D01*
Y65234D01*
Y65288D01*
X134463D01*
Y65342D01*
Y65396D01*
Y65450D01*
Y65504D01*
Y65558D01*
Y65612D01*
Y65666D01*
Y65720D01*
Y65774D01*
Y65828D01*
Y65882D01*
Y65936D01*
Y65991D01*
Y66045D01*
Y66099D01*
Y66153D01*
Y66207D01*
Y66261D01*
Y66315D01*
Y66369D01*
Y66423D01*
Y66477D01*
Y66531D01*
Y66585D01*
Y66639D01*
Y66693D01*
Y66747D01*
Y66802D01*
Y66856D01*
Y66910D01*
Y66964D01*
Y67018D01*
Y67072D01*
Y67126D01*
Y67180D01*
Y67234D01*
Y67288D01*
Y67342D01*
Y67396D01*
Y67450D01*
Y67504D01*
Y67558D01*
Y67612D01*
Y67667D01*
Y67721D01*
Y67775D01*
Y67829D01*
Y67883D01*
Y67937D01*
Y67991D01*
Y68045D01*
Y68099D01*
Y68153D01*
Y68207D01*
Y68261D01*
Y68315D01*
Y68369D01*
Y68423D01*
Y68477D01*
Y68531D01*
Y68585D01*
Y68640D01*
Y68694D01*
Y68748D01*
Y68802D01*
Y68856D01*
Y68910D01*
Y68964D01*
Y69018D01*
Y69072D01*
Y69126D01*
Y69180D01*
Y69234D01*
Y69288D01*
Y69342D01*
Y69397D01*
Y69450D01*
Y69505D01*
Y69559D01*
Y69613D01*
Y69667D01*
Y69721D01*
Y69775D01*
Y69829D01*
Y69883D01*
Y69937D01*
Y69991D01*
Y70045D01*
Y70099D01*
Y70153D01*
Y70207D01*
Y70261D01*
Y70315D01*
Y70370D01*
Y70424D01*
Y70478D01*
Y70532D01*
Y70586D01*
Y70640D01*
Y70694D01*
Y70748D01*
Y70802D01*
Y70856D01*
Y70910D01*
Y70964D01*
Y71018D01*
Y71072D01*
Y71126D01*
Y71180D01*
Y71235D01*
Y71289D01*
Y71343D01*
Y71397D01*
Y71451D01*
Y71505D01*
Y71559D01*
Y71613D01*
Y71667D01*
Y71721D01*
Y71775D01*
Y71829D01*
Y71883D01*
Y71937D01*
Y71991D01*
Y72045D01*
Y72100D01*
Y72154D01*
Y72208D01*
Y72262D01*
Y72316D01*
Y72370D01*
Y72424D01*
Y72478D01*
Y72532D01*
Y72586D01*
Y72640D01*
Y72694D01*
Y72748D01*
Y72802D01*
Y72856D01*
Y72910D01*
Y72965D01*
Y73019D01*
Y73073D01*
Y73127D01*
Y73181D01*
Y73235D01*
Y73289D01*
Y73343D01*
Y73397D01*
Y73451D01*
Y73505D01*
Y73559D01*
Y73613D01*
Y73667D01*
Y73721D01*
Y73776D01*
Y73830D01*
Y73884D01*
Y73938D01*
Y73992D01*
Y74046D01*
Y74100D01*
Y74154D01*
Y74208D01*
Y74262D01*
Y74316D01*
Y74370D01*
Y74424D01*
Y74478D01*
Y74532D01*
Y74586D01*
Y74641D01*
Y74695D01*
Y74749D01*
Y74803D01*
X134409D01*
Y74857D01*
Y74911D01*
X134354D01*
Y74965D01*
X134246D01*
Y75019D01*
D02*
G37*
G36*
X155006D02*
X147275D01*
Y74965D01*
X147221D01*
Y74911D01*
X147167D01*
Y74857D01*
X147113D01*
Y74803D01*
Y74749D01*
Y74695D01*
Y74641D01*
Y74586D01*
Y74532D01*
Y74478D01*
Y74424D01*
Y74370D01*
Y74316D01*
Y74262D01*
Y74208D01*
Y74154D01*
Y74100D01*
Y74046D01*
Y73992D01*
Y73938D01*
Y73884D01*
Y73830D01*
Y73776D01*
Y73721D01*
Y73667D01*
Y73613D01*
Y73559D01*
Y73505D01*
Y73451D01*
Y73397D01*
Y73343D01*
Y73289D01*
Y73235D01*
Y73181D01*
Y73127D01*
Y73073D01*
Y73019D01*
Y72965D01*
Y72910D01*
Y72856D01*
Y72802D01*
Y72748D01*
Y72694D01*
Y72640D01*
Y72586D01*
Y72532D01*
Y72478D01*
Y72424D01*
Y72370D01*
Y72316D01*
Y72262D01*
Y72208D01*
Y72154D01*
Y72100D01*
Y72045D01*
Y71991D01*
Y71937D01*
Y71883D01*
Y71829D01*
Y71775D01*
Y71721D01*
Y71667D01*
Y71613D01*
Y71559D01*
Y71505D01*
Y71451D01*
Y71397D01*
Y71343D01*
Y71289D01*
Y71235D01*
Y71180D01*
Y71126D01*
Y71072D01*
Y71018D01*
Y70964D01*
Y70910D01*
Y70856D01*
Y70802D01*
Y70748D01*
Y70694D01*
Y70640D01*
Y70586D01*
Y70532D01*
Y70478D01*
Y70424D01*
Y70370D01*
Y70315D01*
Y70261D01*
Y70207D01*
Y70153D01*
Y70099D01*
Y70045D01*
Y69991D01*
Y69937D01*
Y69883D01*
Y69829D01*
Y69775D01*
Y69721D01*
Y69667D01*
Y69613D01*
Y69559D01*
Y69505D01*
Y69450D01*
Y69397D01*
Y69342D01*
Y69288D01*
Y69234D01*
Y69180D01*
Y69126D01*
Y69072D01*
Y69018D01*
Y68964D01*
Y68910D01*
Y68856D01*
Y68802D01*
Y68748D01*
Y68694D01*
Y68640D01*
Y68585D01*
Y68531D01*
Y68477D01*
Y68423D01*
Y68369D01*
Y68315D01*
Y68261D01*
Y68207D01*
Y68153D01*
Y68099D01*
Y68045D01*
Y67991D01*
Y67937D01*
Y67883D01*
Y67829D01*
Y67775D01*
Y67721D01*
Y67667D01*
Y67612D01*
Y67558D01*
Y67504D01*
Y67450D01*
Y67396D01*
Y67342D01*
Y67288D01*
Y67234D01*
Y67180D01*
Y67126D01*
Y67072D01*
Y67018D01*
Y66964D01*
Y66910D01*
Y66856D01*
Y66802D01*
Y66747D01*
Y66693D01*
Y66639D01*
Y66585D01*
Y66531D01*
Y66477D01*
Y66423D01*
Y66369D01*
Y66315D01*
Y66261D01*
Y66207D01*
Y66153D01*
Y66099D01*
Y66045D01*
Y65991D01*
Y65936D01*
Y65882D01*
Y65828D01*
Y65774D01*
Y65720D01*
Y65666D01*
Y65612D01*
Y65558D01*
Y65504D01*
Y65450D01*
Y65396D01*
Y65342D01*
Y65288D01*
Y65234D01*
Y65180D01*
Y65126D01*
Y65071D01*
Y65017D01*
Y64963D01*
Y64909D01*
Y64855D01*
Y64801D01*
Y64747D01*
Y64693D01*
Y64639D01*
Y64585D01*
Y64531D01*
Y64477D01*
Y64423D01*
Y64369D01*
Y64315D01*
Y64261D01*
Y64206D01*
Y64152D01*
Y64098D01*
Y64044D01*
Y63990D01*
Y63936D01*
Y63882D01*
Y63828D01*
Y63774D01*
Y63720D01*
Y63666D01*
Y63612D01*
Y63558D01*
Y63504D01*
Y63450D01*
X147167D01*
Y63396D01*
X147221D01*
Y63341D01*
X147275D01*
Y63287D01*
X147383D01*
Y63233D01*
X154844D01*
Y63287D01*
X155114D01*
Y63341D01*
X155277D01*
Y63396D01*
X155331D01*
Y63450D01*
X155385D01*
Y63504D01*
X155439D01*
Y63558D01*
X155493D01*
Y63612D01*
X155547D01*
Y63666D01*
X155601D01*
Y63720D01*
X155655D01*
Y63774D01*
X155709D01*
Y63828D01*
X155763D01*
Y63882D01*
X155817D01*
Y63936D01*
X155871D01*
Y63990D01*
X155925D01*
Y64044D01*
X155979D01*
Y64098D01*
X156033D01*
Y64152D01*
X156087D01*
Y64206D01*
X156141D01*
Y64261D01*
X156196D01*
Y64315D01*
X156250D01*
Y64369D01*
X156304D01*
Y64423D01*
X156358D01*
Y64477D01*
X156412D01*
Y64531D01*
X156466D01*
Y64585D01*
X156520D01*
Y64639D01*
X156574D01*
Y64693D01*
X156628D01*
Y64747D01*
X156682D01*
Y64801D01*
X156736D01*
Y64855D01*
X156790D01*
Y64909D01*
X156844D01*
Y64963D01*
X156898D01*
Y65017D01*
Y65071D01*
X156952D01*
Y65126D01*
Y65180D01*
Y65234D01*
Y65288D01*
X157007D01*
Y65342D01*
Y65396D01*
Y65450D01*
Y65504D01*
Y65558D01*
Y65612D01*
Y65666D01*
Y65720D01*
Y65774D01*
Y65828D01*
Y65882D01*
Y65936D01*
Y65991D01*
Y66045D01*
Y66099D01*
Y66153D01*
Y66207D01*
Y66261D01*
Y66315D01*
Y66369D01*
Y66423D01*
Y66477D01*
Y66531D01*
Y66585D01*
Y66639D01*
Y66693D01*
Y66747D01*
Y66802D01*
Y66856D01*
Y66910D01*
Y66964D01*
Y67018D01*
Y67072D01*
Y67126D01*
Y67180D01*
Y67234D01*
Y67288D01*
Y67342D01*
Y67396D01*
Y67450D01*
Y67504D01*
Y67558D01*
Y67612D01*
Y67667D01*
Y67721D01*
Y67775D01*
Y67829D01*
Y67883D01*
Y67937D01*
Y67991D01*
Y68045D01*
Y68099D01*
Y68153D01*
Y68207D01*
Y68261D01*
Y68315D01*
Y68369D01*
Y68423D01*
Y68477D01*
Y68531D01*
Y68585D01*
Y68640D01*
Y68694D01*
Y68748D01*
Y68802D01*
Y68856D01*
Y68910D01*
Y68964D01*
Y69018D01*
Y69072D01*
Y69126D01*
Y69180D01*
Y69234D01*
Y69288D01*
Y69342D01*
Y69397D01*
Y69450D01*
Y69505D01*
Y69559D01*
Y69613D01*
Y69667D01*
Y69721D01*
Y69775D01*
Y69829D01*
Y69883D01*
Y69937D01*
Y69991D01*
Y70045D01*
Y70099D01*
Y70153D01*
Y70207D01*
Y70261D01*
Y70315D01*
Y70370D01*
Y70424D01*
Y70478D01*
Y70532D01*
Y70586D01*
Y70640D01*
Y70694D01*
Y70748D01*
Y70802D01*
Y70856D01*
Y70910D01*
Y70964D01*
Y71018D01*
Y71072D01*
Y71126D01*
Y71180D01*
Y71235D01*
Y71289D01*
Y71343D01*
Y71397D01*
Y71451D01*
Y71505D01*
Y71559D01*
Y71613D01*
Y71667D01*
Y71721D01*
Y71775D01*
Y71829D01*
Y71883D01*
Y71937D01*
Y71991D01*
Y72045D01*
Y72100D01*
Y72154D01*
Y72208D01*
Y72262D01*
Y72316D01*
Y72370D01*
Y72424D01*
Y72478D01*
Y72532D01*
Y72586D01*
Y72640D01*
Y72694D01*
Y72748D01*
Y72802D01*
Y72856D01*
Y72910D01*
Y72965D01*
X156952D01*
Y73019D01*
Y73073D01*
Y73127D01*
Y73181D01*
X156898D01*
Y73235D01*
Y73289D01*
Y73343D01*
X156844D01*
Y73397D01*
X156790D01*
Y73451D01*
X156736D01*
Y73505D01*
X156682D01*
Y73559D01*
X156628D01*
Y73613D01*
X156574D01*
Y73667D01*
X156520D01*
Y73721D01*
X156466D01*
Y73776D01*
X156412D01*
Y73830D01*
X156358D01*
Y73884D01*
X156304D01*
Y73938D01*
X156250D01*
Y73992D01*
X156196D01*
Y74046D01*
X156141D01*
Y74100D01*
X156087D01*
Y74154D01*
X156033D01*
Y74208D01*
X155979D01*
Y74262D01*
X155925D01*
Y74316D01*
X155871D01*
Y74370D01*
X155817D01*
Y74424D01*
X155763D01*
Y74478D01*
X155709D01*
Y74532D01*
X155655D01*
Y74586D01*
X155601D01*
Y74641D01*
X155547D01*
Y74695D01*
X155493D01*
Y74749D01*
X155439D01*
Y74803D01*
X155385D01*
Y74857D01*
X155331D01*
Y74911D01*
X155222D01*
Y74965D01*
X155006D01*
Y75019D01*
D02*
G37*
G36*
X123056D02*
X116190D01*
Y74965D01*
X116027D01*
Y74911D01*
X115919D01*
Y74857D01*
X115865D01*
Y74803D01*
X115811D01*
Y74749D01*
X115757D01*
Y74695D01*
X115703D01*
Y74641D01*
X115649D01*
Y74586D01*
X115595D01*
Y74532D01*
X115541D01*
Y74478D01*
X115487D01*
Y74424D01*
X115433D01*
Y74370D01*
X115379D01*
Y74316D01*
X115325D01*
Y74262D01*
X115271D01*
Y74208D01*
X115217D01*
Y74154D01*
X115163D01*
Y74100D01*
X115108D01*
Y74046D01*
X115054D01*
Y73992D01*
X115000D01*
Y73938D01*
X114946D01*
Y73884D01*
X114892D01*
Y73830D01*
X114838D01*
Y73776D01*
X114784D01*
Y73721D01*
X114730D01*
Y73667D01*
X114676D01*
Y73613D01*
X114622D01*
Y73559D01*
X114568D01*
Y73505D01*
X114514D01*
Y73451D01*
X114460D01*
Y73397D01*
X114406D01*
Y73343D01*
X114352D01*
Y73289D01*
Y73235D01*
X114297D01*
Y73181D01*
Y73127D01*
Y73073D01*
X114243D01*
Y73019D01*
Y72965D01*
Y72910D01*
Y72856D01*
Y72802D01*
Y72748D01*
Y72694D01*
Y72640D01*
Y72586D01*
Y72532D01*
Y72478D01*
Y72424D01*
Y72370D01*
Y72316D01*
Y72262D01*
Y72208D01*
Y72154D01*
Y72100D01*
Y72045D01*
Y71991D01*
Y71937D01*
Y71883D01*
Y71829D01*
Y71775D01*
Y71721D01*
Y71667D01*
Y71613D01*
Y71559D01*
Y71505D01*
Y71451D01*
Y71397D01*
Y71343D01*
Y71289D01*
Y71235D01*
Y71180D01*
Y71126D01*
Y71072D01*
Y71018D01*
Y70964D01*
Y70910D01*
Y70856D01*
Y70802D01*
Y70748D01*
Y70694D01*
Y70640D01*
Y70586D01*
Y70532D01*
Y70478D01*
Y70424D01*
Y70370D01*
Y70315D01*
Y70261D01*
Y70207D01*
Y70153D01*
Y70099D01*
Y70045D01*
Y69991D01*
Y69937D01*
Y69883D01*
Y69829D01*
Y69775D01*
Y69721D01*
Y69667D01*
Y69613D01*
Y69559D01*
Y69505D01*
Y69450D01*
Y69397D01*
Y69342D01*
Y69288D01*
Y69234D01*
Y69180D01*
Y69126D01*
Y69072D01*
Y69018D01*
Y68964D01*
Y68910D01*
Y68856D01*
Y68802D01*
Y68748D01*
Y68694D01*
Y68640D01*
Y68585D01*
Y68531D01*
Y68477D01*
Y68423D01*
Y68369D01*
Y68315D01*
Y68261D01*
Y68207D01*
Y68153D01*
Y68099D01*
Y68045D01*
Y67991D01*
Y67937D01*
Y67883D01*
Y67829D01*
Y67775D01*
Y67721D01*
Y67667D01*
Y67612D01*
Y67558D01*
Y67504D01*
Y67450D01*
Y67396D01*
Y67342D01*
Y67288D01*
Y67234D01*
Y67180D01*
Y67126D01*
Y67072D01*
Y67018D01*
Y66964D01*
Y66910D01*
Y66856D01*
Y66802D01*
Y66747D01*
Y66693D01*
Y66639D01*
Y66585D01*
Y66531D01*
Y66477D01*
Y66423D01*
Y66369D01*
Y66315D01*
Y66261D01*
Y66207D01*
Y66153D01*
Y66099D01*
Y66045D01*
Y65991D01*
Y65936D01*
Y65882D01*
Y65828D01*
Y65774D01*
Y65720D01*
Y65666D01*
Y65612D01*
Y65558D01*
Y65504D01*
Y65450D01*
Y65396D01*
Y65342D01*
Y65288D01*
Y65234D01*
X114297D01*
Y65180D01*
Y65126D01*
Y65071D01*
Y65017D01*
X114352D01*
Y64963D01*
Y64909D01*
X114406D01*
Y64855D01*
X114460D01*
Y64801D01*
X114514D01*
Y64747D01*
X114568D01*
Y64693D01*
X114622D01*
Y64639D01*
X114676D01*
Y64585D01*
X114730D01*
Y64531D01*
X114784D01*
Y64477D01*
X114838D01*
Y64423D01*
X114892D01*
Y64369D01*
X114946D01*
Y64315D01*
X115000D01*
Y64261D01*
X115054D01*
Y64206D01*
X115108D01*
Y64152D01*
X115163D01*
Y64098D01*
X115217D01*
Y64044D01*
X115271D01*
Y63990D01*
X115325D01*
Y63936D01*
X115379D01*
Y63882D01*
X115433D01*
Y63828D01*
X115487D01*
Y63774D01*
X115541D01*
Y63720D01*
X115595D01*
Y63666D01*
X115649D01*
Y63612D01*
X115703D01*
Y63558D01*
X115757D01*
Y63504D01*
X115811D01*
Y63450D01*
X115865D01*
Y63396D01*
X115973D01*
Y63341D01*
X116136D01*
Y63287D01*
X116298D01*
Y63233D01*
X122785D01*
Y63287D01*
X122839D01*
Y63233D01*
X122947D01*
Y63287D01*
X123110D01*
Y63341D01*
X123164D01*
Y63396D01*
X123218D01*
Y63450D01*
Y63504D01*
Y63558D01*
Y63612D01*
Y63666D01*
Y63720D01*
Y63774D01*
Y63828D01*
Y63882D01*
Y63936D01*
Y63990D01*
Y64044D01*
Y64098D01*
Y64152D01*
Y64206D01*
Y64261D01*
Y64315D01*
Y64369D01*
Y64423D01*
Y64477D01*
Y64531D01*
Y64585D01*
Y64639D01*
Y64693D01*
Y64747D01*
Y64801D01*
Y64855D01*
Y64909D01*
Y64963D01*
Y65017D01*
Y65071D01*
Y65126D01*
Y65180D01*
Y65234D01*
Y65288D01*
Y65342D01*
Y65396D01*
Y65450D01*
Y65504D01*
Y65558D01*
Y65612D01*
Y65666D01*
Y65720D01*
Y65774D01*
Y65828D01*
Y65882D01*
Y65936D01*
Y65991D01*
X123164D01*
Y66045D01*
X123110D01*
Y66099D01*
X122947D01*
Y66153D01*
X122731D01*
Y66099D01*
X122677D01*
Y66153D01*
X117325D01*
Y66207D01*
X117271D01*
Y66261D01*
X117217D01*
Y66315D01*
Y66369D01*
Y66423D01*
Y66477D01*
Y66531D01*
Y66585D01*
Y66639D01*
Y66693D01*
Y66747D01*
Y66802D01*
Y66856D01*
Y66910D01*
Y66964D01*
Y67018D01*
Y67072D01*
Y67126D01*
Y67180D01*
Y67234D01*
Y67288D01*
Y67342D01*
Y67396D01*
Y67450D01*
Y67504D01*
Y67558D01*
Y67612D01*
Y67667D01*
Y67721D01*
Y67775D01*
Y67829D01*
Y67883D01*
Y67937D01*
Y67991D01*
Y68045D01*
Y68099D01*
Y68153D01*
Y68207D01*
Y68261D01*
Y68315D01*
Y68369D01*
Y68423D01*
Y68477D01*
Y68531D01*
Y68585D01*
Y68640D01*
Y68694D01*
Y68748D01*
Y68802D01*
Y68856D01*
Y68910D01*
Y68964D01*
Y69018D01*
Y69072D01*
Y69126D01*
Y69180D01*
Y69234D01*
Y69288D01*
Y69342D01*
Y69397D01*
Y69450D01*
Y69505D01*
Y69559D01*
Y69613D01*
Y69667D01*
Y69721D01*
Y69775D01*
Y69829D01*
Y69883D01*
Y69937D01*
Y69991D01*
Y70045D01*
Y70099D01*
Y70153D01*
Y70207D01*
Y70261D01*
Y70315D01*
Y70370D01*
Y70424D01*
Y70478D01*
Y70532D01*
Y70586D01*
Y70640D01*
Y70694D01*
Y70748D01*
Y70802D01*
Y70856D01*
Y70910D01*
Y70964D01*
Y71018D01*
Y71072D01*
Y71126D01*
Y71180D01*
Y71235D01*
Y71289D01*
Y71343D01*
Y71397D01*
Y71451D01*
Y71505D01*
Y71559D01*
Y71613D01*
Y71667D01*
Y71721D01*
Y71775D01*
Y71829D01*
Y71883D01*
Y71937D01*
Y71991D01*
X117271D01*
Y72045D01*
Y72100D01*
X117379D01*
Y72154D01*
X123002D01*
Y72208D01*
X123110D01*
Y72262D01*
X123164D01*
Y72316D01*
X123218D01*
Y72370D01*
Y72424D01*
Y72478D01*
Y72532D01*
Y72586D01*
Y72640D01*
Y72694D01*
Y72748D01*
Y72802D01*
Y72856D01*
Y72910D01*
Y72965D01*
Y73019D01*
Y73073D01*
Y73127D01*
Y73181D01*
Y73235D01*
Y73289D01*
Y73343D01*
Y73397D01*
Y73451D01*
Y73505D01*
Y73559D01*
Y73613D01*
Y73667D01*
Y73721D01*
Y73776D01*
Y73830D01*
Y73884D01*
Y73938D01*
Y73992D01*
Y74046D01*
Y74100D01*
Y74154D01*
Y74208D01*
Y74262D01*
Y74316D01*
Y74370D01*
Y74424D01*
Y74478D01*
Y74532D01*
Y74586D01*
Y74641D01*
Y74695D01*
Y74749D01*
Y74803D01*
Y74857D01*
X123164D01*
Y74911D01*
X123110D01*
Y74965D01*
X123056D01*
Y75019D01*
D02*
G37*
G36*
X125651Y62260D02*
X123272D01*
Y62206D01*
X123164D01*
Y62152D01*
X123110D01*
Y62098D01*
Y62044D01*
X123056D01*
Y61990D01*
Y61936D01*
Y61882D01*
Y61828D01*
Y61774D01*
Y61720D01*
Y61666D01*
Y61611D01*
Y61557D01*
Y61503D01*
Y61449D01*
Y61395D01*
Y61341D01*
Y61287D01*
Y61233D01*
Y61179D01*
Y61125D01*
Y61071D01*
Y61017D01*
Y60963D01*
Y60909D01*
Y60855D01*
Y60801D01*
Y60747D01*
Y60693D01*
Y60638D01*
Y60584D01*
Y60530D01*
Y60476D01*
Y60422D01*
Y60368D01*
Y60314D01*
Y60260D01*
Y60206D01*
Y60152D01*
Y60098D01*
Y60044D01*
Y59990D01*
Y59936D01*
Y59882D01*
Y59828D01*
Y59773D01*
Y59719D01*
Y59665D01*
Y59611D01*
Y59557D01*
Y59503D01*
Y59449D01*
Y59395D01*
Y59341D01*
Y59287D01*
Y59233D01*
Y59179D01*
Y59125D01*
Y59071D01*
Y59017D01*
Y58963D01*
Y58908D01*
Y58854D01*
Y58800D01*
Y58746D01*
Y58692D01*
Y58638D01*
Y58584D01*
Y58530D01*
Y58476D01*
Y58422D01*
Y58368D01*
Y58314D01*
Y58260D01*
Y58206D01*
Y58152D01*
Y58097D01*
Y58043D01*
Y57989D01*
Y57935D01*
Y57881D01*
Y57827D01*
Y57773D01*
Y57719D01*
Y57665D01*
Y57611D01*
Y57557D01*
Y57503D01*
Y57449D01*
Y57395D01*
Y57341D01*
Y57287D01*
Y57232D01*
Y57178D01*
Y57124D01*
Y57070D01*
Y57016D01*
Y56962D01*
Y56908D01*
Y56854D01*
Y56800D01*
Y56746D01*
Y56692D01*
Y56638D01*
Y56584D01*
Y56530D01*
Y56476D01*
Y56422D01*
Y56367D01*
Y56313D01*
Y56259D01*
Y56205D01*
Y56151D01*
Y56097D01*
Y56043D01*
Y55989D01*
Y55935D01*
Y55881D01*
Y55827D01*
Y55773D01*
Y55719D01*
Y55665D01*
Y55611D01*
Y55557D01*
Y55502D01*
Y55449D01*
Y55394D01*
Y55340D01*
Y55286D01*
Y55232D01*
Y55178D01*
Y55124D01*
Y55070D01*
Y55016D01*
Y54962D01*
Y54908D01*
Y54854D01*
Y54800D01*
Y54746D01*
Y54692D01*
Y54637D01*
Y54584D01*
Y54529D01*
Y54475D01*
Y54421D01*
Y54367D01*
Y54313D01*
Y54259D01*
Y54205D01*
Y54151D01*
Y54097D01*
Y54043D01*
Y53989D01*
Y53935D01*
Y53881D01*
Y53827D01*
Y53772D01*
Y53719D01*
Y53664D01*
Y53610D01*
Y53556D01*
Y53502D01*
Y53448D01*
Y53394D01*
X121217D01*
Y53448D01*
Y53502D01*
Y53556D01*
Y53610D01*
Y53664D01*
Y53719D01*
Y53772D01*
Y53827D01*
Y53881D01*
Y53935D01*
Y53989D01*
Y54043D01*
Y54097D01*
Y54151D01*
Y54205D01*
Y54259D01*
Y54313D01*
Y54367D01*
Y54421D01*
Y54475D01*
Y54529D01*
Y54584D01*
Y54637D01*
Y54692D01*
Y54746D01*
Y54800D01*
Y54854D01*
Y54908D01*
Y54962D01*
Y55016D01*
Y55070D01*
Y55124D01*
Y55178D01*
Y55232D01*
Y55286D01*
Y55340D01*
Y55394D01*
Y55449D01*
Y55502D01*
Y55557D01*
Y55611D01*
Y55665D01*
Y55719D01*
Y55773D01*
Y55827D01*
Y55881D01*
Y55935D01*
Y55989D01*
Y56043D01*
Y56097D01*
Y56151D01*
Y56205D01*
Y56259D01*
Y56313D01*
Y56367D01*
Y56422D01*
Y56476D01*
Y56530D01*
Y56584D01*
Y56638D01*
Y56692D01*
Y56746D01*
Y56800D01*
Y56854D01*
Y56908D01*
Y56962D01*
Y57016D01*
Y57070D01*
Y57124D01*
Y57178D01*
Y57232D01*
Y57287D01*
Y57341D01*
Y57395D01*
Y57449D01*
Y57503D01*
Y57557D01*
Y57611D01*
Y57665D01*
Y57719D01*
Y57773D01*
Y57827D01*
Y57881D01*
Y57935D01*
Y57989D01*
Y58043D01*
Y58097D01*
Y58152D01*
Y58206D01*
Y58260D01*
Y58314D01*
Y58368D01*
Y58422D01*
Y58476D01*
Y58530D01*
Y58584D01*
Y58638D01*
Y58692D01*
Y58746D01*
Y58800D01*
Y58854D01*
Y58908D01*
Y58963D01*
Y59017D01*
Y59071D01*
Y59125D01*
Y59179D01*
Y59233D01*
Y59287D01*
Y59341D01*
Y59395D01*
Y59449D01*
Y59503D01*
Y59557D01*
Y59611D01*
Y59665D01*
Y59719D01*
Y59773D01*
Y59828D01*
Y59882D01*
Y59936D01*
Y59990D01*
Y60044D01*
Y60098D01*
Y60152D01*
Y60206D01*
Y60260D01*
Y60314D01*
Y60368D01*
Y60422D01*
Y60476D01*
Y60530D01*
Y60584D01*
Y60638D01*
Y60693D01*
Y60747D01*
Y60801D01*
Y60855D01*
Y60909D01*
Y60963D01*
Y61017D01*
Y61071D01*
Y61125D01*
Y61179D01*
Y61233D01*
Y61287D01*
Y61341D01*
Y61395D01*
Y61449D01*
Y61503D01*
Y61557D01*
Y61611D01*
Y61666D01*
Y61720D01*
Y61774D01*
Y61828D01*
Y61882D01*
Y61936D01*
Y61990D01*
Y62044D01*
X121163D01*
Y62098D01*
Y62152D01*
X121109D01*
Y62206D01*
X121055D01*
Y62260D01*
X118406D01*
Y62206D01*
X118298D01*
Y62152D01*
Y62098D01*
X118244D01*
Y62044D01*
Y61990D01*
Y61936D01*
Y61882D01*
Y61828D01*
Y61774D01*
Y61720D01*
Y61666D01*
Y61611D01*
Y61557D01*
Y61503D01*
Y61449D01*
Y61395D01*
Y61341D01*
Y61287D01*
Y61233D01*
Y61179D01*
Y61125D01*
Y61071D01*
Y61017D01*
Y60963D01*
Y60909D01*
Y60855D01*
Y60801D01*
Y60747D01*
Y60693D01*
Y60638D01*
Y60584D01*
Y60530D01*
Y60476D01*
Y60422D01*
Y60368D01*
Y60314D01*
Y60260D01*
Y60206D01*
Y60152D01*
Y60098D01*
Y60044D01*
Y59990D01*
Y59936D01*
Y59882D01*
Y59828D01*
Y59773D01*
Y59719D01*
Y59665D01*
Y59611D01*
Y59557D01*
Y59503D01*
Y59449D01*
Y59395D01*
Y59341D01*
Y59287D01*
Y59233D01*
Y59179D01*
Y59125D01*
Y59071D01*
Y59017D01*
Y58963D01*
Y58908D01*
Y58854D01*
Y58800D01*
Y58746D01*
Y58692D01*
Y58638D01*
Y58584D01*
Y58530D01*
Y58476D01*
Y58422D01*
Y58368D01*
Y58314D01*
Y58260D01*
Y58206D01*
Y58152D01*
Y58097D01*
Y58043D01*
Y57989D01*
Y57935D01*
Y57881D01*
Y57827D01*
Y57773D01*
Y57719D01*
Y57665D01*
Y57611D01*
Y57557D01*
Y57503D01*
Y57449D01*
Y57395D01*
Y57341D01*
Y57287D01*
Y57232D01*
Y57178D01*
Y57124D01*
Y57070D01*
Y57016D01*
Y56962D01*
Y56908D01*
Y56854D01*
Y56800D01*
Y56746D01*
Y56692D01*
Y56638D01*
Y56584D01*
Y56530D01*
Y56476D01*
Y56422D01*
Y56367D01*
Y56313D01*
Y56259D01*
Y56205D01*
Y56151D01*
Y56097D01*
Y56043D01*
Y55989D01*
Y55935D01*
Y55881D01*
Y55827D01*
Y55773D01*
Y55719D01*
Y55665D01*
Y55611D01*
Y55557D01*
Y55502D01*
Y55449D01*
Y55394D01*
Y55340D01*
Y55286D01*
Y55232D01*
Y55178D01*
Y55124D01*
Y55070D01*
Y55016D01*
Y54962D01*
Y54908D01*
Y54854D01*
Y54800D01*
Y54746D01*
Y54692D01*
Y54637D01*
Y54584D01*
Y54529D01*
Y54475D01*
Y54421D01*
Y54367D01*
Y54313D01*
Y54259D01*
Y54205D01*
Y54151D01*
Y54097D01*
Y54043D01*
Y53989D01*
Y53935D01*
Y53881D01*
Y53827D01*
Y53772D01*
Y53719D01*
Y53664D01*
Y53610D01*
Y53556D01*
Y53502D01*
Y53448D01*
Y53394D01*
Y53340D01*
Y53286D01*
Y53232D01*
Y53178D01*
Y53124D01*
Y53070D01*
Y53016D01*
Y52962D01*
Y52908D01*
Y52854D01*
Y52799D01*
Y52745D01*
Y52691D01*
Y52637D01*
Y52583D01*
Y52529D01*
Y52475D01*
Y52421D01*
Y52367D01*
Y52313D01*
Y52259D01*
Y52205D01*
Y52151D01*
Y52097D01*
Y52043D01*
Y51989D01*
Y51934D01*
Y51880D01*
Y51826D01*
Y51772D01*
Y51718D01*
Y51664D01*
Y51610D01*
Y51556D01*
Y51502D01*
Y51448D01*
Y51394D01*
Y51340D01*
Y51286D01*
Y51232D01*
Y51178D01*
Y51123D01*
Y51069D01*
Y51015D01*
Y50961D01*
Y50907D01*
Y50853D01*
Y50799D01*
Y50745D01*
Y50691D01*
X118298D01*
Y50637D01*
Y50583D01*
X118352D01*
Y50529D01*
X118514D01*
Y50475D01*
X126786D01*
Y50529D01*
Y50583D01*
Y50637D01*
Y50691D01*
Y50745D01*
Y50799D01*
Y50853D01*
Y50907D01*
Y50961D01*
Y51015D01*
Y51069D01*
Y51123D01*
Y51178D01*
Y51232D01*
Y51286D01*
Y51340D01*
Y51394D01*
Y51448D01*
Y51502D01*
Y51556D01*
Y51610D01*
Y51664D01*
Y51718D01*
Y51772D01*
Y51826D01*
Y51880D01*
Y51934D01*
Y51989D01*
Y52043D01*
Y52097D01*
Y52151D01*
Y52205D01*
Y52259D01*
Y52313D01*
Y52367D01*
Y52421D01*
Y52475D01*
Y52529D01*
Y52583D01*
Y52637D01*
Y52691D01*
Y52745D01*
Y52799D01*
Y52854D01*
Y52908D01*
Y52962D01*
Y53016D01*
Y53070D01*
Y53124D01*
Y53178D01*
Y53232D01*
Y53286D01*
Y53340D01*
Y53394D01*
X126624D01*
Y53340D01*
X126570D01*
Y53394D01*
X125813D01*
Y53448D01*
Y53502D01*
Y53556D01*
Y53610D01*
Y53664D01*
Y53719D01*
Y53772D01*
Y53827D01*
Y53881D01*
Y53935D01*
Y53989D01*
Y54043D01*
Y54097D01*
Y54151D01*
Y54205D01*
Y54259D01*
Y54313D01*
Y54367D01*
Y54421D01*
Y54475D01*
Y54529D01*
Y54584D01*
Y54637D01*
Y54692D01*
Y54746D01*
Y54800D01*
Y54854D01*
Y54908D01*
Y54962D01*
Y55016D01*
Y55070D01*
Y55124D01*
Y55178D01*
Y55232D01*
Y55286D01*
Y55340D01*
Y55394D01*
Y55449D01*
Y55502D01*
Y55557D01*
Y55611D01*
Y55665D01*
Y55719D01*
Y55773D01*
Y55827D01*
Y55881D01*
Y55935D01*
Y55989D01*
Y56043D01*
Y56097D01*
Y56151D01*
Y56205D01*
Y56259D01*
Y56313D01*
Y56367D01*
Y56422D01*
Y56476D01*
Y56530D01*
Y56584D01*
Y56638D01*
Y56692D01*
Y56746D01*
Y56800D01*
Y56854D01*
Y56908D01*
Y56962D01*
Y57016D01*
Y57070D01*
Y57124D01*
Y57178D01*
Y57232D01*
Y57287D01*
Y57341D01*
Y57395D01*
Y57449D01*
Y57503D01*
Y57557D01*
Y57611D01*
Y57665D01*
Y57719D01*
Y57773D01*
Y57827D01*
Y57881D01*
Y57935D01*
Y57989D01*
Y58043D01*
Y58097D01*
Y58152D01*
Y58206D01*
Y58260D01*
Y58314D01*
Y58368D01*
Y58422D01*
Y58476D01*
Y58530D01*
Y58584D01*
Y58638D01*
Y58692D01*
Y58746D01*
Y58800D01*
Y58854D01*
Y58908D01*
Y58963D01*
Y59017D01*
Y59071D01*
Y59125D01*
Y59179D01*
Y59233D01*
Y59287D01*
Y59341D01*
Y59395D01*
Y59449D01*
Y59503D01*
Y59557D01*
Y59611D01*
Y59665D01*
Y59719D01*
Y59773D01*
Y59828D01*
Y59882D01*
Y59936D01*
Y59990D01*
Y60044D01*
Y60098D01*
Y60152D01*
Y60206D01*
Y60260D01*
Y60314D01*
Y60368D01*
Y60422D01*
Y60476D01*
Y60530D01*
Y60584D01*
Y60638D01*
Y60693D01*
Y60747D01*
Y60801D01*
Y60855D01*
Y60909D01*
Y60963D01*
Y61017D01*
Y61071D01*
Y61125D01*
Y61179D01*
Y61233D01*
Y61287D01*
Y61341D01*
Y61395D01*
Y61449D01*
Y61503D01*
Y61557D01*
Y61611D01*
Y61666D01*
Y61720D01*
Y61774D01*
Y61828D01*
Y61882D01*
Y61936D01*
Y61990D01*
Y62044D01*
Y62098D01*
X125759D01*
Y62152D01*
X125705D01*
Y62206D01*
X125651D01*
Y62260D01*
D02*
G37*
G36*
X140788D02*
X133922D01*
Y62206D01*
X133706D01*
Y62152D01*
X133598D01*
Y62098D01*
X133544D01*
Y62044D01*
X133490D01*
Y61990D01*
X133435D01*
Y61936D01*
X133381D01*
Y61882D01*
X133327D01*
Y61828D01*
X133273D01*
Y61774D01*
X133219D01*
Y61720D01*
X133165D01*
Y61666D01*
X133111D01*
Y61611D01*
X133057D01*
Y61557D01*
X133003D01*
Y61503D01*
X132949D01*
Y61449D01*
X132895D01*
Y61395D01*
X132841D01*
Y61341D01*
X132787D01*
Y61287D01*
X132733D01*
Y61233D01*
X132679D01*
Y61179D01*
X132624D01*
Y61125D01*
X132571D01*
Y61071D01*
X132516D01*
Y61017D01*
X132462D01*
Y60963D01*
X132408D01*
Y60909D01*
X132354D01*
Y60855D01*
X132300D01*
Y60801D01*
X132246D01*
Y60747D01*
X132192D01*
Y60693D01*
X132138D01*
Y60638D01*
X132084D01*
Y60584D01*
Y60530D01*
X132030D01*
Y60476D01*
Y60422D01*
X131976D01*
Y60368D01*
Y60314D01*
Y60260D01*
Y60206D01*
Y60152D01*
X131922D01*
Y60098D01*
Y60044D01*
Y59990D01*
Y59936D01*
Y59882D01*
Y59828D01*
Y59773D01*
Y59719D01*
Y59665D01*
Y59611D01*
Y59557D01*
Y59503D01*
Y59449D01*
Y59395D01*
Y59341D01*
Y59287D01*
Y59233D01*
Y59179D01*
Y59125D01*
Y59071D01*
Y59017D01*
Y58963D01*
Y58908D01*
Y58854D01*
Y58800D01*
Y58746D01*
Y58692D01*
Y58638D01*
Y58584D01*
Y58530D01*
Y58476D01*
Y58422D01*
Y58368D01*
Y58314D01*
Y58260D01*
Y58206D01*
Y58152D01*
Y58097D01*
Y58043D01*
Y57989D01*
Y57935D01*
Y57881D01*
Y57827D01*
Y57773D01*
Y57719D01*
Y57665D01*
Y57611D01*
Y57557D01*
Y57503D01*
Y57449D01*
Y57395D01*
Y57341D01*
Y57287D01*
Y57232D01*
Y57178D01*
Y57124D01*
Y57070D01*
Y57016D01*
Y56962D01*
Y56908D01*
Y56854D01*
Y56800D01*
Y56746D01*
Y56692D01*
Y56638D01*
Y56584D01*
Y56530D01*
Y56476D01*
Y56422D01*
Y56367D01*
Y56313D01*
Y56259D01*
Y56205D01*
Y56151D01*
Y56097D01*
Y56043D01*
Y55989D01*
Y55935D01*
Y55881D01*
Y55827D01*
Y55773D01*
Y55719D01*
Y55665D01*
Y55611D01*
Y55557D01*
Y55502D01*
Y55449D01*
Y55394D01*
Y55340D01*
Y55286D01*
Y55232D01*
Y55178D01*
Y55124D01*
Y55070D01*
Y55016D01*
Y54962D01*
Y54908D01*
Y54854D01*
Y54800D01*
Y54746D01*
Y54692D01*
Y54637D01*
Y54584D01*
Y54529D01*
Y54475D01*
Y54421D01*
Y54367D01*
Y54313D01*
Y54259D01*
Y54205D01*
Y54151D01*
Y54097D01*
Y54043D01*
Y53989D01*
Y53935D01*
Y53881D01*
Y53827D01*
Y53772D01*
Y53719D01*
Y53664D01*
Y53610D01*
Y53556D01*
Y53502D01*
Y53448D01*
Y53394D01*
Y53340D01*
Y53286D01*
Y53232D01*
Y53178D01*
Y53124D01*
Y53070D01*
Y53016D01*
Y52962D01*
Y52908D01*
Y52854D01*
Y52799D01*
Y52745D01*
Y52691D01*
Y52637D01*
X131976D01*
Y52583D01*
Y52529D01*
Y52475D01*
Y52421D01*
Y52367D01*
X132030D01*
Y52313D01*
Y52259D01*
Y52205D01*
X132084D01*
Y52151D01*
X132138D01*
Y52097D01*
X132192D01*
Y52043D01*
X132246D01*
Y51989D01*
X132300D01*
Y51934D01*
X132354D01*
Y51880D01*
X132408D01*
Y51826D01*
X132462D01*
Y51772D01*
X132516D01*
Y51718D01*
X132571D01*
Y51664D01*
X132624D01*
Y51610D01*
X132679D01*
Y51556D01*
X132733D01*
Y51502D01*
X132787D01*
Y51448D01*
X132841D01*
Y51394D01*
X132895D01*
Y51340D01*
X132949D01*
Y51286D01*
X133003D01*
Y51232D01*
X133057D01*
Y51178D01*
X133111D01*
Y51123D01*
X133165D01*
Y51069D01*
X133219D01*
Y51015D01*
X133273D01*
Y50961D01*
X133327D01*
Y50907D01*
X133381D01*
Y50853D01*
X133435D01*
Y50799D01*
X133490D01*
Y50745D01*
X133544D01*
Y50691D01*
X133598D01*
Y50637D01*
X133706D01*
Y50583D01*
X133868D01*
Y50529D01*
X134138D01*
Y50475D01*
X140463D01*
Y50529D01*
X140518D01*
Y50475D01*
X140680D01*
Y50529D01*
X140788D01*
Y50583D01*
X140842D01*
Y50637D01*
X140896D01*
Y50691D01*
Y50745D01*
X140950D01*
Y50799D01*
Y50853D01*
Y50907D01*
Y50961D01*
Y51015D01*
Y51069D01*
Y51123D01*
Y51178D01*
Y51232D01*
Y51286D01*
Y51340D01*
Y51394D01*
Y51448D01*
Y51502D01*
Y51556D01*
Y51610D01*
Y51664D01*
Y51718D01*
Y51772D01*
Y51826D01*
Y51880D01*
Y51934D01*
Y51989D01*
Y52043D01*
Y52097D01*
Y52151D01*
Y52205D01*
Y52259D01*
Y52313D01*
Y52367D01*
Y52421D01*
Y52475D01*
Y52529D01*
Y52583D01*
Y52637D01*
Y52691D01*
Y52745D01*
Y52799D01*
Y52854D01*
Y52908D01*
Y52962D01*
Y53016D01*
Y53070D01*
X140896D01*
Y53124D01*
X140842D01*
Y53178D01*
X140788D01*
Y53232D01*
X134949D01*
Y53286D01*
X134895D01*
Y53340D01*
Y53394D01*
Y53448D01*
Y53502D01*
Y53556D01*
Y53610D01*
Y53664D01*
Y53719D01*
Y53772D01*
Y53827D01*
Y53881D01*
Y53935D01*
Y53989D01*
Y54043D01*
Y54097D01*
Y54151D01*
Y54205D01*
Y54259D01*
Y54313D01*
Y54367D01*
Y54421D01*
Y54475D01*
Y54529D01*
Y54584D01*
Y54637D01*
Y54692D01*
Y54746D01*
Y54800D01*
Y54854D01*
Y54908D01*
Y54962D01*
Y55016D01*
Y55070D01*
Y55124D01*
Y55178D01*
X134949D01*
Y55232D01*
X139923D01*
Y55286D01*
X140031D01*
Y55340D01*
Y55394D01*
X140085D01*
Y55449D01*
Y55502D01*
Y55557D01*
Y55611D01*
Y55665D01*
Y55719D01*
Y55773D01*
Y55827D01*
Y55881D01*
Y55935D01*
Y55989D01*
Y56043D01*
Y56097D01*
Y56151D01*
Y56205D01*
Y56259D01*
Y56313D01*
Y56367D01*
Y56422D01*
Y56476D01*
Y56530D01*
Y56584D01*
Y56638D01*
Y56692D01*
Y56746D01*
Y56800D01*
Y56854D01*
Y56908D01*
Y56962D01*
Y57016D01*
Y57070D01*
Y57124D01*
Y57178D01*
Y57232D01*
Y57287D01*
Y57341D01*
Y57395D01*
X140031D01*
Y57449D01*
Y57503D01*
X139923D01*
Y57557D01*
X134949D01*
Y57611D01*
X134895D01*
Y57665D01*
Y57719D01*
Y57773D01*
Y57827D01*
Y57881D01*
Y57935D01*
Y57989D01*
Y58043D01*
Y58097D01*
Y58152D01*
Y58206D01*
Y58260D01*
Y58314D01*
Y58368D01*
Y58422D01*
Y58476D01*
Y58530D01*
Y58584D01*
Y58638D01*
Y58692D01*
Y58746D01*
Y58800D01*
Y58854D01*
Y58908D01*
Y58963D01*
Y59017D01*
Y59071D01*
Y59125D01*
Y59179D01*
Y59233D01*
Y59287D01*
Y59341D01*
Y59395D01*
Y59449D01*
X134949D01*
Y59503D01*
X140734D01*
Y59557D01*
X140842D01*
Y59611D01*
X140896D01*
Y59665D01*
Y59719D01*
X140950D01*
Y59773D01*
Y59828D01*
Y59882D01*
Y59936D01*
Y59990D01*
Y60044D01*
Y60098D01*
Y60152D01*
Y60206D01*
Y60260D01*
Y60314D01*
Y60368D01*
Y60422D01*
Y60476D01*
Y60530D01*
Y60584D01*
Y60638D01*
Y60693D01*
Y60747D01*
Y60801D01*
Y60855D01*
Y60909D01*
Y60963D01*
Y61017D01*
Y61071D01*
Y61125D01*
Y61179D01*
Y61233D01*
Y61287D01*
Y61341D01*
Y61395D01*
Y61449D01*
Y61503D01*
Y61557D01*
Y61611D01*
Y61666D01*
Y61720D01*
Y61774D01*
Y61828D01*
Y61882D01*
Y61936D01*
Y61990D01*
Y62044D01*
X140896D01*
Y62098D01*
Y62152D01*
X140842D01*
Y62206D01*
X140788D01*
Y62260D01*
D02*
G37*
G36*
X116784D02*
X114081D01*
Y62206D01*
X114027D01*
Y62152D01*
X113973D01*
Y62098D01*
Y62044D01*
X113919D01*
Y61990D01*
Y61936D01*
Y61882D01*
Y61828D01*
Y61774D01*
Y61720D01*
Y61666D01*
Y61611D01*
Y61557D01*
Y61503D01*
Y61449D01*
Y61395D01*
Y61341D01*
Y61287D01*
Y61233D01*
Y61179D01*
Y61125D01*
Y61071D01*
Y61017D01*
Y60963D01*
Y60909D01*
Y60855D01*
Y60801D01*
Y60747D01*
Y60693D01*
Y60638D01*
Y60584D01*
Y60530D01*
Y60476D01*
Y60422D01*
Y60368D01*
Y60314D01*
Y60260D01*
Y60206D01*
Y60152D01*
Y60098D01*
Y60044D01*
Y59990D01*
Y59936D01*
Y59882D01*
Y59828D01*
Y59773D01*
Y59719D01*
Y59665D01*
Y59611D01*
Y59557D01*
Y59503D01*
Y59449D01*
Y59395D01*
Y59341D01*
Y59287D01*
Y59233D01*
Y59179D01*
Y59125D01*
Y59071D01*
Y59017D01*
Y58963D01*
Y58908D01*
Y58854D01*
Y58800D01*
Y58746D01*
Y58692D01*
Y58638D01*
Y58584D01*
Y58530D01*
Y58476D01*
Y58422D01*
Y58368D01*
Y58314D01*
Y58260D01*
Y58206D01*
Y58152D01*
Y58097D01*
Y58043D01*
Y57989D01*
Y57935D01*
Y57881D01*
Y57827D01*
Y57773D01*
Y57719D01*
Y57665D01*
Y57611D01*
Y57557D01*
Y57503D01*
Y57449D01*
Y57395D01*
Y57341D01*
Y57287D01*
Y57232D01*
Y57178D01*
Y57124D01*
Y57070D01*
Y57016D01*
Y56962D01*
Y56908D01*
Y56854D01*
Y56800D01*
Y56746D01*
Y56692D01*
Y56638D01*
Y56584D01*
Y56530D01*
Y56476D01*
Y56422D01*
Y56367D01*
Y56313D01*
Y56259D01*
Y56205D01*
Y56151D01*
Y56097D01*
Y56043D01*
Y55989D01*
Y55935D01*
Y55881D01*
Y55827D01*
Y55773D01*
Y55719D01*
Y55665D01*
Y55611D01*
Y55557D01*
Y55502D01*
Y55449D01*
Y55394D01*
Y55340D01*
Y55286D01*
Y55232D01*
Y55178D01*
Y55124D01*
Y55070D01*
Y55016D01*
Y54962D01*
Y54908D01*
Y54854D01*
Y54800D01*
Y54746D01*
Y54692D01*
Y54637D01*
Y54584D01*
Y54529D01*
Y54475D01*
Y54421D01*
Y54367D01*
Y54313D01*
Y54259D01*
Y54205D01*
Y54151D01*
Y54097D01*
Y54043D01*
Y53989D01*
Y53935D01*
Y53881D01*
Y53827D01*
Y53772D01*
Y53719D01*
Y53664D01*
Y53610D01*
Y53556D01*
Y53502D01*
Y53448D01*
Y53394D01*
Y53340D01*
Y53286D01*
Y53232D01*
Y53178D01*
Y53124D01*
Y53070D01*
Y53016D01*
Y52962D01*
Y52908D01*
Y52854D01*
Y52799D01*
Y52745D01*
Y52691D01*
Y52637D01*
Y52583D01*
Y52529D01*
Y52475D01*
Y52421D01*
Y52367D01*
Y52313D01*
Y52259D01*
Y52205D01*
Y52151D01*
Y52097D01*
Y52043D01*
Y51989D01*
Y51934D01*
Y51880D01*
Y51826D01*
Y51772D01*
Y51718D01*
Y51664D01*
Y51610D01*
Y51556D01*
Y51502D01*
Y51448D01*
Y51394D01*
Y51340D01*
Y51286D01*
Y51232D01*
Y51178D01*
Y51123D01*
Y51069D01*
Y51015D01*
Y50961D01*
Y50907D01*
Y50853D01*
Y50799D01*
Y50745D01*
X113973D01*
Y50691D01*
Y50637D01*
X114027D01*
Y50583D01*
Y50529D01*
X114189D01*
Y50475D01*
X116676D01*
Y50529D01*
X116784D01*
Y50583D01*
X116838D01*
Y50637D01*
X116893D01*
Y50691D01*
Y50745D01*
Y50799D01*
Y50853D01*
Y50907D01*
Y50961D01*
Y51015D01*
Y51069D01*
Y51123D01*
Y51178D01*
Y51232D01*
Y51286D01*
Y51340D01*
Y51394D01*
Y51448D01*
Y51502D01*
Y51556D01*
Y51610D01*
Y51664D01*
Y51718D01*
Y51772D01*
Y51826D01*
Y51880D01*
Y51934D01*
Y51989D01*
Y52043D01*
Y52097D01*
Y52151D01*
Y52205D01*
Y52259D01*
Y52313D01*
Y52367D01*
Y52421D01*
Y52475D01*
Y52529D01*
Y52583D01*
Y52637D01*
Y52691D01*
Y52745D01*
Y52799D01*
Y52854D01*
Y52908D01*
Y52962D01*
Y53016D01*
Y53070D01*
Y53124D01*
Y53178D01*
Y53232D01*
Y53286D01*
Y53340D01*
Y53394D01*
Y53448D01*
Y53502D01*
Y53556D01*
Y53610D01*
Y53664D01*
Y53719D01*
Y53772D01*
Y53827D01*
Y53881D01*
Y53935D01*
Y53989D01*
Y54043D01*
Y54097D01*
Y54151D01*
Y54205D01*
Y54259D01*
Y54313D01*
Y54367D01*
Y54421D01*
Y54475D01*
Y54529D01*
Y54584D01*
Y54637D01*
Y54692D01*
Y54746D01*
Y54800D01*
Y54854D01*
Y54908D01*
Y54962D01*
Y55016D01*
Y55070D01*
Y55124D01*
Y55178D01*
Y55232D01*
Y55286D01*
Y55340D01*
Y55394D01*
Y55449D01*
Y55502D01*
Y55557D01*
Y55611D01*
Y55665D01*
Y55719D01*
Y55773D01*
Y55827D01*
Y55881D01*
Y55935D01*
Y55989D01*
Y56043D01*
Y56097D01*
Y56151D01*
Y56205D01*
Y56259D01*
Y56313D01*
Y56367D01*
Y56422D01*
Y56476D01*
Y56530D01*
Y56584D01*
Y56638D01*
Y56692D01*
Y56746D01*
Y56800D01*
Y56854D01*
Y56908D01*
Y56962D01*
Y57016D01*
Y57070D01*
Y57124D01*
Y57178D01*
Y57232D01*
Y57287D01*
Y57341D01*
Y57395D01*
Y57449D01*
Y57503D01*
Y57557D01*
Y57611D01*
Y57665D01*
Y57719D01*
Y57773D01*
Y57827D01*
Y57881D01*
Y57935D01*
Y57989D01*
Y58043D01*
Y58097D01*
Y58152D01*
Y58206D01*
Y58260D01*
Y58314D01*
Y58368D01*
Y58422D01*
Y58476D01*
Y58530D01*
Y58584D01*
Y58638D01*
Y58692D01*
Y58746D01*
Y58800D01*
Y58854D01*
Y58908D01*
Y58963D01*
Y59017D01*
Y59071D01*
Y59125D01*
Y59179D01*
Y59233D01*
Y59287D01*
Y59341D01*
Y59395D01*
Y59449D01*
Y59503D01*
Y59557D01*
Y59611D01*
Y59665D01*
Y59719D01*
Y59773D01*
Y59828D01*
Y59882D01*
Y59936D01*
Y59990D01*
Y60044D01*
Y60098D01*
Y60152D01*
Y60206D01*
Y60260D01*
Y60314D01*
Y60368D01*
Y60422D01*
Y60476D01*
Y60530D01*
Y60584D01*
Y60638D01*
Y60693D01*
Y60747D01*
Y60801D01*
Y60855D01*
Y60909D01*
Y60963D01*
Y61017D01*
Y61071D01*
Y61125D01*
Y61179D01*
Y61233D01*
Y61287D01*
Y61341D01*
Y61395D01*
Y61449D01*
Y61503D01*
Y61557D01*
Y61611D01*
Y61666D01*
Y61720D01*
Y61774D01*
Y61828D01*
Y61882D01*
Y61936D01*
Y61990D01*
Y62044D01*
Y62098D01*
Y62152D01*
X116838D01*
Y62206D01*
X116784D01*
Y62260D01*
D02*
G37*
G36*
X110081D02*
X107432D01*
Y62206D01*
X107378D01*
Y62152D01*
X107324D01*
Y62098D01*
X107269D01*
Y62044D01*
Y61990D01*
Y61936D01*
Y61882D01*
Y61828D01*
Y61774D01*
Y61720D01*
Y61666D01*
Y61611D01*
Y61557D01*
Y61503D01*
Y61449D01*
Y61395D01*
Y61341D01*
Y61287D01*
Y61233D01*
Y61179D01*
Y61125D01*
Y61071D01*
Y61017D01*
Y60963D01*
Y60909D01*
Y60855D01*
Y60801D01*
Y60747D01*
Y60693D01*
Y60638D01*
Y60584D01*
Y60530D01*
Y60476D01*
Y60422D01*
Y60368D01*
Y60314D01*
Y60260D01*
Y60206D01*
Y60152D01*
Y60098D01*
Y60044D01*
Y59990D01*
Y59936D01*
Y59882D01*
Y59828D01*
Y59773D01*
Y59719D01*
Y59665D01*
Y59611D01*
Y59557D01*
Y59503D01*
Y59449D01*
Y59395D01*
Y59341D01*
Y59287D01*
Y59233D01*
Y59179D01*
Y59125D01*
Y59071D01*
Y59017D01*
Y58963D01*
Y58908D01*
Y58854D01*
Y58800D01*
Y58746D01*
Y58692D01*
Y58638D01*
Y58584D01*
Y58530D01*
Y58476D01*
Y58422D01*
Y58368D01*
Y58314D01*
Y58260D01*
Y58206D01*
Y58152D01*
Y58097D01*
Y58043D01*
Y57989D01*
Y57935D01*
Y57881D01*
Y57827D01*
Y57773D01*
Y57719D01*
Y57665D01*
Y57611D01*
Y57557D01*
Y57503D01*
Y57449D01*
Y57395D01*
Y57341D01*
Y57287D01*
Y57232D01*
Y57178D01*
Y57124D01*
Y57070D01*
Y57016D01*
Y56962D01*
Y56908D01*
Y56854D01*
Y56800D01*
Y56746D01*
Y56692D01*
Y56638D01*
Y56584D01*
Y56530D01*
Y56476D01*
Y56422D01*
Y56367D01*
Y56313D01*
Y56259D01*
Y56205D01*
Y56151D01*
Y56097D01*
Y56043D01*
Y55989D01*
Y55935D01*
Y55881D01*
Y55827D01*
Y55773D01*
Y55719D01*
Y55665D01*
Y55611D01*
Y55557D01*
Y55502D01*
Y55449D01*
Y55394D01*
Y55340D01*
Y55286D01*
Y55232D01*
Y55178D01*
Y55124D01*
Y55070D01*
Y55016D01*
Y54962D01*
Y54908D01*
Y54854D01*
Y54800D01*
Y54746D01*
Y54692D01*
Y54637D01*
Y54584D01*
Y54529D01*
Y54475D01*
Y54421D01*
Y54367D01*
Y54313D01*
Y54259D01*
Y54205D01*
Y54151D01*
Y54097D01*
Y54043D01*
Y53989D01*
Y53935D01*
Y53881D01*
Y53827D01*
Y53772D01*
Y53719D01*
Y53664D01*
Y53610D01*
X107215D01*
Y53556D01*
Y53502D01*
X107161D01*
Y53448D01*
X107107D01*
Y53394D01*
X104512D01*
Y53340D01*
X104404D01*
Y53286D01*
X104350D01*
Y53232D01*
X104296D01*
Y53178D01*
X104242D01*
Y53124D01*
Y53070D01*
Y53016D01*
Y52962D01*
Y52908D01*
Y52854D01*
Y52799D01*
Y52745D01*
Y52691D01*
Y52637D01*
Y52583D01*
Y52529D01*
Y52475D01*
Y52421D01*
Y52367D01*
Y52313D01*
Y52259D01*
Y52205D01*
Y52151D01*
Y52097D01*
Y52043D01*
Y51989D01*
Y51934D01*
Y51880D01*
Y51826D01*
Y51772D01*
Y51718D01*
Y51664D01*
Y51610D01*
Y51556D01*
Y51502D01*
Y51448D01*
Y51394D01*
Y51340D01*
Y51286D01*
Y51232D01*
Y51178D01*
Y51123D01*
Y51069D01*
Y51015D01*
Y50961D01*
Y50907D01*
Y50853D01*
Y50799D01*
Y50745D01*
Y50691D01*
X104296D01*
Y50637D01*
Y50583D01*
X104350D01*
Y50529D01*
X104512D01*
Y50475D01*
X112838D01*
Y50529D01*
X112892D01*
Y50475D01*
X113000D01*
Y50529D01*
X113108D01*
Y50583D01*
X113162D01*
Y50637D01*
X113216D01*
Y50691D01*
Y50745D01*
Y50799D01*
X113270D01*
Y50853D01*
Y50907D01*
Y50961D01*
Y51015D01*
Y51069D01*
Y51123D01*
Y51178D01*
Y51232D01*
Y51286D01*
Y51340D01*
Y51394D01*
Y51448D01*
Y51502D01*
Y51556D01*
Y51610D01*
Y51664D01*
Y51718D01*
Y51772D01*
Y51826D01*
Y51880D01*
Y51934D01*
Y51989D01*
Y52043D01*
Y52097D01*
Y52151D01*
Y52205D01*
Y52259D01*
Y52313D01*
Y52367D01*
Y52421D01*
Y52475D01*
Y52529D01*
Y52583D01*
Y52637D01*
Y52691D01*
Y52745D01*
Y52799D01*
Y52854D01*
Y52908D01*
Y52962D01*
Y53016D01*
Y53070D01*
X113216D01*
Y53124D01*
Y53178D01*
Y53232D01*
X113162D01*
Y53286D01*
X113108D01*
Y53340D01*
X112946D01*
Y53394D01*
X110351D01*
Y53448D01*
X110297D01*
Y53502D01*
X110243D01*
Y53556D01*
Y53610D01*
Y53664D01*
Y53719D01*
Y53772D01*
Y53827D01*
Y53881D01*
Y53935D01*
Y53989D01*
Y54043D01*
Y54097D01*
Y54151D01*
Y54205D01*
Y54259D01*
Y54313D01*
Y54367D01*
Y54421D01*
Y54475D01*
Y54529D01*
Y54584D01*
Y54637D01*
Y54692D01*
Y54746D01*
Y54800D01*
Y54854D01*
Y54908D01*
Y54962D01*
Y55016D01*
Y55070D01*
Y55124D01*
Y55178D01*
Y55232D01*
Y55286D01*
Y55340D01*
Y55394D01*
Y55449D01*
Y55502D01*
Y55557D01*
Y55611D01*
Y55665D01*
Y55719D01*
Y55773D01*
Y55827D01*
Y55881D01*
Y55935D01*
Y55989D01*
Y56043D01*
Y56097D01*
Y56151D01*
Y56205D01*
Y56259D01*
Y56313D01*
Y56367D01*
Y56422D01*
Y56476D01*
Y56530D01*
Y56584D01*
Y56638D01*
Y56692D01*
Y56746D01*
Y56800D01*
Y56854D01*
Y56908D01*
Y56962D01*
Y57016D01*
Y57070D01*
Y57124D01*
Y57178D01*
Y57232D01*
Y57287D01*
Y57341D01*
Y57395D01*
Y57449D01*
Y57503D01*
Y57557D01*
Y57611D01*
Y57665D01*
Y57719D01*
Y57773D01*
Y57827D01*
Y57881D01*
Y57935D01*
Y57989D01*
Y58043D01*
Y58097D01*
Y58152D01*
Y58206D01*
Y58260D01*
Y58314D01*
Y58368D01*
Y58422D01*
Y58476D01*
Y58530D01*
Y58584D01*
Y58638D01*
Y58692D01*
Y58746D01*
Y58800D01*
Y58854D01*
Y58908D01*
Y58963D01*
Y59017D01*
Y59071D01*
Y59125D01*
Y59179D01*
Y59233D01*
Y59287D01*
Y59341D01*
Y59395D01*
Y59449D01*
Y59503D01*
Y59557D01*
Y59611D01*
Y59665D01*
Y59719D01*
Y59773D01*
Y59828D01*
Y59882D01*
Y59936D01*
Y59990D01*
Y60044D01*
Y60098D01*
Y60152D01*
Y60206D01*
Y60260D01*
Y60314D01*
Y60368D01*
Y60422D01*
Y60476D01*
Y60530D01*
Y60584D01*
Y60638D01*
Y60693D01*
Y60747D01*
Y60801D01*
Y60855D01*
Y60909D01*
Y60963D01*
Y61017D01*
Y61071D01*
Y61125D01*
Y61179D01*
Y61233D01*
Y61287D01*
Y61341D01*
Y61395D01*
Y61449D01*
Y61503D01*
Y61557D01*
Y61611D01*
Y61666D01*
Y61720D01*
Y61774D01*
Y61828D01*
Y61882D01*
Y61936D01*
Y61990D01*
X110189D01*
Y62044D01*
Y62098D01*
Y62152D01*
X110135D01*
Y62206D01*
X110081D01*
Y62260D01*
D02*
G37*
G36*
X122731Y70964D02*
X122623D01*
Y70910D01*
X122569D01*
Y70856D01*
X122515D01*
Y70802D01*
X122461D01*
Y70748D01*
X122407D01*
Y70694D01*
X122353D01*
Y70640D01*
X122299D01*
Y70586D01*
X122245D01*
Y70532D01*
X122191D01*
Y70478D01*
X122136D01*
Y70424D01*
Y70370D01*
X122082D01*
Y70315D01*
X122028D01*
Y70261D01*
Y70207D01*
X121974D01*
Y70153D01*
X121920D01*
Y70099D01*
Y70045D01*
Y69991D01*
Y69937D01*
Y69883D01*
Y69829D01*
Y69775D01*
Y69721D01*
Y69667D01*
Y69613D01*
Y69559D01*
Y69505D01*
Y69450D01*
Y69397D01*
Y69342D01*
Y69288D01*
Y69234D01*
Y69180D01*
Y69126D01*
Y69072D01*
Y69018D01*
Y68964D01*
Y68910D01*
Y68856D01*
Y68802D01*
Y68748D01*
Y68694D01*
Y68640D01*
Y68585D01*
Y68531D01*
Y68477D01*
Y68423D01*
Y68369D01*
Y68315D01*
Y68261D01*
Y68207D01*
Y68153D01*
Y68099D01*
Y68045D01*
Y67991D01*
Y67937D01*
Y67883D01*
Y67829D01*
Y67775D01*
Y67721D01*
X121974D01*
Y67667D01*
Y67612D01*
X122028D01*
Y67558D01*
Y67504D01*
X122082D01*
Y67450D01*
X122136D01*
Y67396D01*
Y67342D01*
X122191D01*
Y67288D01*
X122245D01*
Y67234D01*
X122299D01*
Y67180D01*
X122353D01*
Y67126D01*
X122407D01*
Y67072D01*
X122461D01*
Y67018D01*
X122515D01*
Y66964D01*
X122569D01*
Y66910D01*
X122623D01*
Y66856D01*
X122677D01*
Y66802D01*
X122731D01*
Y66747D01*
X122785D01*
Y66693D01*
X122839D01*
Y66639D01*
X122893D01*
Y66585D01*
X122947D01*
Y66531D01*
X123002D01*
Y66477D01*
X123110D01*
Y66423D01*
X123164D01*
Y66369D01*
X123218D01*
Y66315D01*
X123272D01*
Y66261D01*
X123326D01*
Y66207D01*
X123380D01*
Y66153D01*
X123434D01*
Y66099D01*
X123488D01*
Y66045D01*
X123542D01*
Y65991D01*
X123596D01*
Y65936D01*
X123650D01*
Y65882D01*
X123704D01*
Y65828D01*
X123758D01*
Y65774D01*
X123812D01*
Y65720D01*
X123866D01*
Y65666D01*
X123921D01*
Y65612D01*
X123975D01*
Y65558D01*
X124029D01*
Y65504D01*
X124083D01*
Y65450D01*
X124137D01*
Y65396D01*
X124191D01*
Y65342D01*
X124245D01*
Y65288D01*
X124299D01*
Y65234D01*
X124353D01*
Y65180D01*
X124407D01*
Y65126D01*
X124461D01*
Y65071D01*
X124515D01*
Y65017D01*
X124569D01*
Y64963D01*
X124623D01*
Y64909D01*
X124677D01*
Y64855D01*
X124732D01*
Y64801D01*
X124785D01*
Y64747D01*
X124840D01*
Y64693D01*
X124894D01*
Y64639D01*
X124948D01*
Y64585D01*
X125002D01*
Y64531D01*
X125056D01*
Y64477D01*
X125110D01*
Y64423D01*
X125164D01*
Y64369D01*
X125218D01*
Y64315D01*
X125272D01*
Y64261D01*
X125326D01*
Y64206D01*
X125380D01*
Y64152D01*
X125434D01*
Y64098D01*
X125488D01*
Y64044D01*
X125542D01*
Y63990D01*
X125596D01*
Y63936D01*
X125651D01*
Y63882D01*
X125705D01*
Y63828D01*
X125759D01*
Y63774D01*
X125813D01*
Y63720D01*
X125867D01*
Y63666D01*
X125921D01*
Y63612D01*
X125975D01*
Y63558D01*
X126029D01*
Y63504D01*
X126083D01*
Y63450D01*
X126137D01*
Y63396D01*
X126191D01*
Y63341D01*
X126245D01*
Y63287D01*
X126299D01*
Y63233D01*
X126353D01*
Y63179D01*
X126407D01*
Y63125D01*
X126462D01*
Y63071D01*
X126515D01*
Y63017D01*
X126570D01*
Y62963D01*
X126624D01*
Y62909D01*
X126678D01*
Y62855D01*
X126786D01*
Y62801D01*
X126840D01*
Y62747D01*
X126894D01*
Y62693D01*
X126948D01*
Y62639D01*
X127002D01*
Y62585D01*
X127056D01*
Y62531D01*
X127110D01*
Y62476D01*
X127164D01*
Y62423D01*
X127218D01*
Y62368D01*
X127272D01*
Y62314D01*
X127326D01*
Y62260D01*
X127381D01*
Y62206D01*
X127435D01*
Y62152D01*
X127489D01*
Y62098D01*
X127543D01*
Y62044D01*
X127597D01*
Y61990D01*
X127651D01*
Y61936D01*
X127705D01*
Y61882D01*
Y61828D01*
Y61774D01*
Y61720D01*
Y61666D01*
Y61611D01*
Y61557D01*
Y61503D01*
Y61449D01*
Y61395D01*
Y61341D01*
Y61287D01*
Y61233D01*
Y61179D01*
Y61125D01*
Y61071D01*
Y61017D01*
Y60963D01*
Y60909D01*
Y60855D01*
Y60801D01*
Y60747D01*
Y60693D01*
Y60638D01*
Y60584D01*
Y60530D01*
Y60476D01*
Y60422D01*
Y60368D01*
Y60314D01*
Y60260D01*
Y60206D01*
Y60152D01*
Y60098D01*
Y60044D01*
Y59990D01*
Y59936D01*
Y59882D01*
Y59828D01*
Y59773D01*
Y59719D01*
Y59665D01*
Y59611D01*
Y59557D01*
Y59503D01*
Y59449D01*
Y59395D01*
Y59341D01*
Y59287D01*
Y59233D01*
Y59179D01*
Y59125D01*
Y59071D01*
Y59017D01*
Y58963D01*
Y58908D01*
Y58854D01*
Y58800D01*
Y58746D01*
Y58692D01*
Y58638D01*
Y58584D01*
Y58530D01*
Y58476D01*
Y58422D01*
Y58368D01*
Y58314D01*
Y58260D01*
Y58206D01*
Y58152D01*
Y58097D01*
Y58043D01*
Y57989D01*
Y57935D01*
Y57881D01*
Y57827D01*
Y57773D01*
Y57719D01*
Y57665D01*
Y57611D01*
Y57557D01*
Y57503D01*
Y57449D01*
Y57395D01*
Y57341D01*
Y57287D01*
Y57232D01*
Y57178D01*
Y57124D01*
Y57070D01*
Y57016D01*
Y56962D01*
Y56908D01*
Y56854D01*
Y56800D01*
Y56746D01*
Y56692D01*
Y56638D01*
Y56584D01*
Y56530D01*
Y56476D01*
Y56422D01*
Y56367D01*
Y56313D01*
Y56259D01*
Y56205D01*
Y56151D01*
Y56097D01*
Y56043D01*
Y55989D01*
Y55935D01*
Y55881D01*
Y55827D01*
Y55773D01*
Y55719D01*
Y55665D01*
Y55611D01*
Y55557D01*
Y55502D01*
Y55449D01*
Y55394D01*
Y55340D01*
Y55286D01*
Y55232D01*
Y55178D01*
Y55124D01*
Y55070D01*
Y55016D01*
Y54962D01*
Y54908D01*
Y54854D01*
Y54800D01*
Y54746D01*
Y54692D01*
Y54637D01*
Y54584D01*
Y54529D01*
Y54475D01*
Y54421D01*
Y54367D01*
Y54313D01*
Y54259D01*
Y54205D01*
Y54151D01*
Y54097D01*
Y54043D01*
Y53989D01*
Y53935D01*
Y53881D01*
Y53827D01*
Y53772D01*
Y53719D01*
Y53664D01*
Y53610D01*
Y53556D01*
Y53502D01*
Y53448D01*
Y53394D01*
Y53340D01*
Y53286D01*
Y53232D01*
Y53178D01*
Y53124D01*
Y53070D01*
Y53016D01*
Y52962D01*
Y52908D01*
Y52854D01*
Y52799D01*
Y52745D01*
Y52691D01*
Y52637D01*
Y52583D01*
Y52529D01*
Y52475D01*
Y52421D01*
Y52367D01*
Y52313D01*
Y52259D01*
Y52205D01*
Y52151D01*
Y52097D01*
Y52043D01*
Y51989D01*
Y51934D01*
Y51880D01*
Y51826D01*
Y51772D01*
Y51718D01*
Y51664D01*
Y51610D01*
Y51556D01*
Y51502D01*
Y51448D01*
Y51394D01*
Y51340D01*
Y51286D01*
Y51232D01*
Y51178D01*
Y51123D01*
Y51069D01*
Y51015D01*
Y50961D01*
Y50907D01*
Y50853D01*
Y50799D01*
Y50745D01*
Y50691D01*
Y50637D01*
Y50583D01*
Y50529D01*
Y50475D01*
Y50421D01*
Y50367D01*
Y50313D01*
Y50258D01*
Y50204D01*
Y50150D01*
Y50096D01*
Y50042D01*
Y49988D01*
Y49934D01*
Y49880D01*
Y49826D01*
Y49772D01*
Y49718D01*
Y49664D01*
Y49610D01*
Y49556D01*
Y49502D01*
Y49448D01*
Y49393D01*
Y49339D01*
Y49285D01*
Y49231D01*
Y49177D01*
Y49123D01*
Y49069D01*
Y49015D01*
Y48961D01*
Y48907D01*
Y48853D01*
Y48799D01*
Y48745D01*
Y48691D01*
Y48637D01*
Y48583D01*
Y48529D01*
Y48474D01*
Y48420D01*
Y48366D01*
Y48312D01*
Y48258D01*
Y48204D01*
Y48150D01*
Y48096D01*
Y48042D01*
Y47988D01*
Y47934D01*
Y47880D01*
Y47826D01*
Y47772D01*
Y47718D01*
Y47664D01*
Y47609D01*
Y47555D01*
Y47501D01*
Y47447D01*
Y47393D01*
Y47339D01*
Y47285D01*
Y47231D01*
Y47177D01*
Y47123D01*
Y47069D01*
Y47015D01*
Y46961D01*
Y46907D01*
Y46853D01*
Y46799D01*
Y46744D01*
Y46690D01*
Y46636D01*
Y46582D01*
Y46528D01*
Y46474D01*
Y46420D01*
Y46366D01*
Y46312D01*
Y46258D01*
Y46204D01*
Y46150D01*
Y46096D01*
Y46042D01*
Y45988D01*
Y45933D01*
Y45880D01*
Y45825D01*
Y45771D01*
Y45717D01*
Y45663D01*
Y45609D01*
Y45555D01*
Y45501D01*
Y45447D01*
Y45393D01*
Y45339D01*
Y45285D01*
Y45231D01*
Y45177D01*
Y45123D01*
Y45068D01*
Y45015D01*
Y44960D01*
Y44906D01*
Y44852D01*
Y44798D01*
Y44744D01*
Y44690D01*
Y44636D01*
Y44582D01*
Y44528D01*
Y44474D01*
Y44420D01*
Y44366D01*
Y44312D01*
Y44258D01*
Y44204D01*
Y44150D01*
Y44095D01*
Y44041D01*
X128678D01*
Y44095D01*
X128894D01*
Y44150D01*
X129002D01*
Y44204D01*
X129056D01*
Y44258D01*
X129111D01*
Y44312D01*
X129165D01*
Y44366D01*
X129219D01*
Y44420D01*
X129273D01*
Y44474D01*
X129327D01*
Y44528D01*
X129381D01*
Y44582D01*
X129435D01*
Y44636D01*
X129489D01*
Y44690D01*
X129543D01*
Y44744D01*
X129597D01*
Y44798D01*
X129651D01*
Y44852D01*
X129705D01*
Y44906D01*
X129759D01*
Y44960D01*
X129813D01*
Y45015D01*
X129867D01*
Y45068D01*
X129921D01*
Y45123D01*
X129975D01*
Y45177D01*
X130029D01*
Y45231D01*
X130084D01*
Y45285D01*
X130138D01*
Y45339D01*
X130192D01*
Y45393D01*
X130246D01*
Y45447D01*
X130300D01*
Y45501D01*
X130354D01*
Y45555D01*
X130408D01*
Y45609D01*
X130462D01*
Y45663D01*
X130516D01*
Y45717D01*
Y45771D01*
X130570D01*
Y45825D01*
Y45880D01*
Y45933D01*
Y45988D01*
X130624D01*
Y46042D01*
Y46096D01*
Y46150D01*
Y46204D01*
Y46258D01*
Y46312D01*
Y46366D01*
Y46420D01*
Y46474D01*
Y46528D01*
Y46582D01*
Y46636D01*
Y46690D01*
Y46744D01*
Y46799D01*
Y46853D01*
Y46907D01*
Y46961D01*
Y47015D01*
Y47069D01*
Y47123D01*
Y47177D01*
Y47231D01*
Y47285D01*
Y47339D01*
Y47393D01*
Y47447D01*
Y47501D01*
Y47555D01*
Y47609D01*
Y47664D01*
Y47718D01*
Y47772D01*
Y47826D01*
Y47880D01*
Y47934D01*
Y47988D01*
Y48042D01*
Y48096D01*
Y48150D01*
Y48204D01*
Y48258D01*
Y48312D01*
Y48366D01*
Y48420D01*
Y48474D01*
Y48529D01*
Y48583D01*
Y48637D01*
Y48691D01*
Y48745D01*
Y48799D01*
Y48853D01*
Y48907D01*
Y48961D01*
Y49015D01*
Y49069D01*
Y49123D01*
Y49177D01*
Y49231D01*
Y49285D01*
Y49339D01*
Y49393D01*
Y49448D01*
Y49502D01*
Y49556D01*
Y49610D01*
Y49664D01*
Y49718D01*
Y49772D01*
Y49826D01*
Y49880D01*
Y49934D01*
Y49988D01*
Y50042D01*
Y50096D01*
Y50150D01*
Y50204D01*
Y50258D01*
Y50313D01*
Y50367D01*
Y50421D01*
Y50475D01*
Y50529D01*
Y50583D01*
Y50637D01*
Y50691D01*
Y50745D01*
Y50799D01*
Y50853D01*
Y50907D01*
Y50961D01*
Y51015D01*
Y51069D01*
Y51123D01*
Y51178D01*
Y51232D01*
Y51286D01*
Y51340D01*
Y51394D01*
Y51448D01*
Y51502D01*
Y51556D01*
Y51610D01*
Y51664D01*
Y51718D01*
Y51772D01*
Y51826D01*
Y51880D01*
Y51934D01*
Y51989D01*
Y52043D01*
Y52097D01*
Y52151D01*
Y52205D01*
Y52259D01*
Y52313D01*
Y52367D01*
Y52421D01*
Y52475D01*
Y52529D01*
Y52583D01*
Y52637D01*
Y52691D01*
Y52745D01*
Y52799D01*
Y52854D01*
Y52908D01*
Y52962D01*
Y53016D01*
Y53070D01*
Y53124D01*
Y53178D01*
Y53232D01*
Y53286D01*
Y53340D01*
Y53394D01*
Y53448D01*
Y53502D01*
Y53556D01*
Y53610D01*
Y53664D01*
Y53719D01*
Y53772D01*
Y53827D01*
Y53881D01*
Y53935D01*
Y53989D01*
Y54043D01*
Y54097D01*
Y54151D01*
Y54205D01*
Y54259D01*
Y54313D01*
Y54367D01*
Y54421D01*
Y54475D01*
Y54529D01*
Y54584D01*
Y54637D01*
Y54692D01*
Y54746D01*
Y54800D01*
Y54854D01*
Y54908D01*
Y54962D01*
Y55016D01*
Y55070D01*
Y55124D01*
Y55178D01*
Y55232D01*
Y55286D01*
Y55340D01*
Y55394D01*
Y55449D01*
Y55502D01*
Y55557D01*
Y55611D01*
Y55665D01*
Y55719D01*
Y55773D01*
Y55827D01*
Y55881D01*
Y55935D01*
Y55989D01*
Y56043D01*
Y56097D01*
Y56151D01*
Y56205D01*
Y56259D01*
Y56313D01*
Y56367D01*
Y56422D01*
Y56476D01*
Y56530D01*
Y56584D01*
Y56638D01*
Y56692D01*
Y56746D01*
Y56800D01*
Y56854D01*
Y56908D01*
Y56962D01*
Y57016D01*
Y57070D01*
Y57124D01*
Y57178D01*
Y57232D01*
Y57287D01*
Y57341D01*
Y57395D01*
Y57449D01*
Y57503D01*
Y57557D01*
Y57611D01*
Y57665D01*
Y57719D01*
Y57773D01*
Y57827D01*
Y57881D01*
Y57935D01*
Y57989D01*
Y58043D01*
Y58097D01*
Y58152D01*
Y58206D01*
Y58260D01*
Y58314D01*
Y58368D01*
Y58422D01*
Y58476D01*
Y58530D01*
Y58584D01*
Y58638D01*
Y58692D01*
Y58746D01*
Y58800D01*
Y58854D01*
Y58908D01*
Y58963D01*
Y59017D01*
Y59071D01*
Y59125D01*
Y59179D01*
Y59233D01*
Y59287D01*
Y59341D01*
Y59395D01*
Y59449D01*
Y59503D01*
Y59557D01*
Y59611D01*
Y59665D01*
Y59719D01*
Y59773D01*
Y59828D01*
Y59882D01*
Y59936D01*
Y59990D01*
Y60044D01*
Y60098D01*
Y60152D01*
Y60206D01*
Y60260D01*
Y60314D01*
Y60368D01*
Y60422D01*
Y60476D01*
Y60530D01*
Y60584D01*
Y60638D01*
Y60693D01*
Y60747D01*
Y60801D01*
Y60855D01*
Y60909D01*
Y60963D01*
Y61017D01*
Y61071D01*
Y61125D01*
Y61179D01*
Y61233D01*
Y61287D01*
Y61341D01*
Y61395D01*
Y61449D01*
Y61503D01*
Y61557D01*
Y61611D01*
Y61666D01*
Y61720D01*
Y61774D01*
Y61828D01*
Y61882D01*
Y61936D01*
Y61990D01*
Y62044D01*
Y62098D01*
Y62152D01*
Y62206D01*
Y62260D01*
Y62314D01*
Y62368D01*
Y62423D01*
Y62476D01*
Y62531D01*
Y62585D01*
Y62639D01*
Y62693D01*
Y62747D01*
Y62801D01*
X130570D01*
Y62855D01*
Y62909D01*
Y62963D01*
Y63017D01*
X130516D01*
Y63071D01*
Y63125D01*
X130462D01*
Y63179D01*
Y63233D01*
X130408D01*
Y63287D01*
Y63341D01*
X130354D01*
Y63396D01*
X130300D01*
Y63450D01*
Y63504D01*
X130246D01*
Y63558D01*
X130192D01*
Y63612D01*
X130138D01*
Y63666D01*
X130084D01*
Y63720D01*
X130029D01*
Y63774D01*
X129975D01*
Y63828D01*
X129921D01*
Y63882D01*
X129867D01*
Y63936D01*
X129813D01*
Y63990D01*
X129759D01*
Y64044D01*
X129705D01*
Y64098D01*
X129651D01*
Y64152D01*
X129597D01*
Y64206D01*
X129543D01*
Y64261D01*
X129489D01*
Y64315D01*
X129435D01*
Y64369D01*
X129381D01*
Y64423D01*
X129327D01*
Y64477D01*
X129273D01*
Y64531D01*
X129219D01*
Y64585D01*
X129165D01*
Y64639D01*
X129111D01*
Y64693D01*
X129056D01*
Y64747D01*
X129002D01*
Y64801D01*
X128948D01*
Y64855D01*
X128894D01*
Y64909D01*
X128840D01*
Y64963D01*
X128786D01*
Y65017D01*
X128732D01*
Y65071D01*
X128678D01*
Y65126D01*
X128570D01*
Y65180D01*
X128516D01*
Y65234D01*
X128462D01*
Y65288D01*
X128408D01*
Y65342D01*
X128354D01*
Y65396D01*
X128300D01*
Y65450D01*
X128245D01*
Y65504D01*
X128191D01*
Y65558D01*
X128137D01*
Y65612D01*
X128083D01*
Y65666D01*
X128029D01*
Y65720D01*
X127975D01*
Y65774D01*
X127921D01*
Y65828D01*
X127867D01*
Y65882D01*
X127813D01*
Y65936D01*
X127759D01*
Y65991D01*
X127705D01*
Y66045D01*
X127651D01*
Y66099D01*
X127597D01*
Y66153D01*
X127543D01*
Y66207D01*
X127489D01*
Y66261D01*
X127435D01*
Y66315D01*
X127381D01*
Y66369D01*
X127326D01*
Y66423D01*
X127272D01*
Y66477D01*
X127218D01*
Y66531D01*
X127164D01*
Y66585D01*
X127110D01*
Y66639D01*
X127056D01*
Y66693D01*
X127002D01*
Y66747D01*
X126948D01*
Y66802D01*
X126894D01*
Y66856D01*
X126840D01*
Y66910D01*
X126786D01*
Y66964D01*
X126732D01*
Y67018D01*
X126678D01*
Y67072D01*
X126624D01*
Y67126D01*
X126570D01*
Y67180D01*
X126515D01*
Y67234D01*
X126462D01*
Y67288D01*
X126407D01*
Y67342D01*
X126353D01*
Y67396D01*
X126299D01*
Y67450D01*
X126245D01*
Y67504D01*
X126191D01*
Y67558D01*
X126137D01*
Y67612D01*
X126083D01*
Y67667D01*
X126029D01*
Y67721D01*
X125975D01*
Y67775D01*
X125921D01*
Y67829D01*
X125867D01*
Y67883D01*
X125813D01*
Y67937D01*
X125759D01*
Y67991D01*
X125705D01*
Y68045D01*
X125651D01*
Y68099D01*
X125596D01*
Y68153D01*
X125542D01*
Y68207D01*
X125488D01*
Y68261D01*
X125434D01*
Y68315D01*
X125380D01*
Y68369D01*
X125326D01*
Y68423D01*
X125272D01*
Y68477D01*
X125218D01*
Y68531D01*
X125164D01*
Y68585D01*
X125110D01*
Y68640D01*
X125056D01*
Y68694D01*
X125002D01*
Y68748D01*
X124948D01*
Y68802D01*
X124894D01*
Y68856D01*
X124840D01*
Y68910D01*
X124785D01*
Y68964D01*
X124732D01*
Y69018D01*
X124677D01*
Y69072D01*
X124623D01*
Y69126D01*
X124569D01*
Y69180D01*
X124515D01*
Y69234D01*
X124461D01*
Y69288D01*
X124407D01*
Y69342D01*
X124353D01*
Y69397D01*
X124299D01*
Y69450D01*
X124245D01*
Y69505D01*
X124191D01*
Y69559D01*
X124137D01*
Y69613D01*
X124083D01*
Y69667D01*
X123975D01*
Y69721D01*
X123921D01*
Y69775D01*
X123866D01*
Y69829D01*
X123812D01*
Y69883D01*
X123758D01*
Y69937D01*
X123704D01*
Y69991D01*
X123650D01*
Y70045D01*
X123596D01*
Y70099D01*
X123542D01*
Y70153D01*
X123488D01*
Y70207D01*
X123434D01*
Y70261D01*
X123380D01*
Y70315D01*
X123326D01*
Y70370D01*
X123272D01*
Y70424D01*
X123218D01*
Y70478D01*
X123164D01*
Y70532D01*
X123110D01*
Y70586D01*
X123056D01*
Y70640D01*
X123002D01*
Y70694D01*
X122947D01*
Y70748D01*
X122893D01*
Y70802D01*
X122839D01*
Y70856D01*
X122785D01*
Y70910D01*
X122731D01*
Y70964D01*
D02*
G37*
G36*
X150411Y62423D02*
X149762D01*
Y62368D01*
Y62314D01*
Y62260D01*
Y62206D01*
Y62152D01*
Y62098D01*
Y62044D01*
Y61990D01*
Y61936D01*
Y61882D01*
Y61828D01*
X149708D01*
Y61774D01*
Y61720D01*
Y61666D01*
Y61611D01*
Y61557D01*
Y61503D01*
Y61449D01*
Y61395D01*
Y61341D01*
Y61287D01*
Y61233D01*
Y61179D01*
Y61125D01*
Y61071D01*
Y61017D01*
Y60963D01*
Y60909D01*
X149654D01*
Y60855D01*
Y60801D01*
Y60747D01*
Y60693D01*
Y60638D01*
Y60584D01*
Y60530D01*
Y60476D01*
Y60422D01*
X149600D01*
Y60368D01*
Y60314D01*
Y60260D01*
Y60206D01*
Y60152D01*
Y60098D01*
Y60044D01*
Y59990D01*
Y59936D01*
X149546D01*
Y59882D01*
Y59828D01*
Y59773D01*
Y59719D01*
Y59665D01*
Y59611D01*
Y59557D01*
X149492D01*
Y59503D01*
Y59449D01*
Y59395D01*
Y59341D01*
Y59287D01*
Y59233D01*
X149438D01*
Y59179D01*
Y59125D01*
Y59071D01*
Y59017D01*
Y58963D01*
X149384D01*
Y58908D01*
Y58854D01*
Y58800D01*
Y58746D01*
Y58692D01*
Y58638D01*
X149330D01*
Y58584D01*
Y58530D01*
Y58476D01*
Y58422D01*
X149276D01*
Y58368D01*
Y58314D01*
Y58260D01*
Y58206D01*
Y58152D01*
X149222D01*
Y58097D01*
Y58043D01*
Y57989D01*
Y57935D01*
X149168D01*
Y57881D01*
Y57827D01*
Y57773D01*
Y57719D01*
X149113D01*
Y57665D01*
Y57611D01*
Y57557D01*
Y57503D01*
X149059D01*
Y57449D01*
Y57395D01*
Y57341D01*
Y57287D01*
X149005D01*
Y57232D01*
Y57178D01*
Y57124D01*
X148951D01*
Y57070D01*
Y57016D01*
Y56962D01*
Y56908D01*
X148897D01*
Y56854D01*
Y56800D01*
Y56746D01*
X148843D01*
Y56692D01*
Y56638D01*
Y56584D01*
X148789D01*
Y56530D01*
Y56476D01*
Y56422D01*
Y56367D01*
X148735D01*
Y56313D01*
Y56259D01*
Y56205D01*
X148681D01*
Y56151D01*
Y56097D01*
Y56043D01*
X148627D01*
Y55989D01*
Y55935D01*
X148573D01*
Y55881D01*
Y55827D01*
Y55773D01*
X148519D01*
Y55719D01*
Y55665D01*
Y55611D01*
X148465D01*
Y55557D01*
Y55502D01*
Y55449D01*
X148411D01*
Y55394D01*
Y55340D01*
X148357D01*
Y55286D01*
Y55232D01*
Y55178D01*
X148302D01*
Y55124D01*
Y55070D01*
X148249D01*
Y55016D01*
Y54962D01*
Y54908D01*
X148194D01*
Y54854D01*
Y54800D01*
X148140D01*
Y54746D01*
Y54692D01*
X148086D01*
Y54637D01*
Y54584D01*
Y54529D01*
X148032D01*
Y54475D01*
Y54421D01*
X147978D01*
Y54367D01*
Y54313D01*
X147924D01*
Y54259D01*
Y54205D01*
X147870D01*
Y54151D01*
Y54097D01*
X147816D01*
Y54043D01*
Y53989D01*
X147762D01*
Y53935D01*
Y53881D01*
Y53827D01*
X147708D01*
Y53772D01*
Y53719D01*
X147654D01*
Y53664D01*
Y53610D01*
X147600D01*
Y53556D01*
Y53502D01*
X147546D01*
Y53448D01*
Y53394D01*
X147492D01*
Y53340D01*
X147438D01*
Y53286D01*
Y53232D01*
X147383D01*
Y53178D01*
Y53124D01*
X147329D01*
Y53070D01*
Y53016D01*
X147275D01*
Y52962D01*
Y52908D01*
X147221D01*
Y52854D01*
Y52799D01*
X147167D01*
Y52745D01*
X147113D01*
Y52691D01*
Y52637D01*
X147059D01*
Y52583D01*
Y52529D01*
X147005D01*
Y52475D01*
Y52421D01*
X146951D01*
Y52367D01*
X146897D01*
Y52313D01*
Y52259D01*
X146843D01*
Y52205D01*
Y52151D01*
X146789D01*
Y52097D01*
X146735D01*
Y52043D01*
Y51989D01*
X146681D01*
Y51934D01*
Y51880D01*
X146627D01*
Y51826D01*
X146572D01*
Y51772D01*
Y51718D01*
X146519D01*
Y51664D01*
X146464D01*
Y51610D01*
Y51556D01*
X146410D01*
Y51502D01*
X146356D01*
Y51448D01*
Y51394D01*
X146302D01*
Y51340D01*
X146248D01*
Y51286D01*
Y51232D01*
X146194D01*
Y51178D01*
X146140D01*
Y51123D01*
Y51069D01*
X146086D01*
Y51015D01*
X146032D01*
Y50961D01*
X145978D01*
Y50907D01*
Y50853D01*
X145924D01*
Y50799D01*
X145870D01*
Y50745D01*
Y50691D01*
X145816D01*
Y50637D01*
X145762D01*
Y50583D01*
X145707D01*
Y50529D01*
Y50475D01*
X145653D01*
Y50421D01*
X145599D01*
Y50367D01*
X145545D01*
Y50313D01*
Y50258D01*
X145491D01*
Y50204D01*
X145437D01*
Y50150D01*
X145383D01*
Y50096D01*
X145329D01*
Y50042D01*
Y49988D01*
X145275D01*
Y49934D01*
X145221D01*
Y49880D01*
X145167D01*
Y49826D01*
X145113D01*
Y49772D01*
Y49718D01*
X145059D01*
Y49664D01*
X145005D01*
Y49610D01*
X144951D01*
Y49556D01*
X144897D01*
Y49502D01*
X144843D01*
Y49448D01*
X144789D01*
Y49393D01*
Y49339D01*
X144734D01*
Y49285D01*
X144680D01*
Y49231D01*
X144626D01*
Y49177D01*
X144572D01*
Y49123D01*
X144518D01*
Y49069D01*
X144464D01*
Y49015D01*
X144410D01*
Y48961D01*
X144356D01*
Y48907D01*
X144302D01*
Y48853D01*
Y48799D01*
X144248D01*
Y48745D01*
X144194D01*
Y48691D01*
X144140D01*
Y48637D01*
X144086D01*
Y48583D01*
X144032D01*
Y48529D01*
X143977D01*
Y48474D01*
X143923D01*
Y48420D01*
X143869D01*
Y48366D01*
X143815D01*
Y48312D01*
X143761D01*
Y48258D01*
X143707D01*
Y48204D01*
X143653D01*
Y48150D01*
X143599D01*
Y48096D01*
X143545D01*
Y48042D01*
X143491D01*
Y47988D01*
X143437D01*
Y47934D01*
X143383D01*
Y47880D01*
X143275D01*
Y47826D01*
X143221D01*
Y47772D01*
X143167D01*
Y47718D01*
X143113D01*
Y47664D01*
X143059D01*
Y47609D01*
X143004D01*
Y47555D01*
X142950D01*
Y47501D01*
X142896D01*
Y47447D01*
X142842D01*
Y47393D01*
X142734D01*
Y47339D01*
X142680D01*
Y47285D01*
X142626D01*
Y47231D01*
X142572D01*
Y47177D01*
X142518D01*
Y47123D01*
X142464D01*
Y47069D01*
X142356D01*
Y47015D01*
X142302D01*
Y46961D01*
X142248D01*
Y46907D01*
X142193D01*
Y46853D01*
X142085D01*
Y46799D01*
X142031D01*
Y46744D01*
X141977D01*
Y46690D01*
X141923D01*
Y46636D01*
X141815D01*
Y46582D01*
X141761D01*
Y46528D01*
X141707D01*
Y46474D01*
X141599D01*
Y46420D01*
X141545D01*
Y46366D01*
X141491D01*
Y46312D01*
X141383D01*
Y46258D01*
X141329D01*
Y46204D01*
X141220D01*
Y46150D01*
X141166D01*
Y46096D01*
X141112D01*
Y46042D01*
X141004D01*
Y45988D01*
X140950D01*
Y45933D01*
X140842D01*
Y45880D01*
X140788D01*
Y45825D01*
X140680D01*
Y45771D01*
X140626D01*
Y45717D01*
X140518D01*
Y45663D01*
X140463D01*
Y45609D01*
X140355D01*
Y45555D01*
X140301D01*
Y45501D01*
X140193D01*
Y45447D01*
X140085D01*
Y45393D01*
X140031D01*
Y45339D01*
X139923D01*
Y45285D01*
X139815D01*
Y45231D01*
X139761D01*
Y45177D01*
X139653D01*
Y45123D01*
X139544D01*
Y45068D01*
X139436D01*
Y45015D01*
X139382D01*
Y44960D01*
X139274D01*
Y44906D01*
X139166D01*
Y44852D01*
X139058D01*
Y44798D01*
X138950D01*
Y44744D01*
X138842D01*
Y44690D01*
X138733D01*
Y44636D01*
X138625D01*
Y44582D01*
X138517D01*
Y44528D01*
X138463D01*
Y44474D01*
X138355D01*
Y44420D01*
X138193D01*
Y44366D01*
X138085D01*
Y44312D01*
X137977D01*
Y44258D01*
X137868D01*
Y44204D01*
X137760D01*
Y44150D01*
X137598D01*
Y44095D01*
X137490D01*
Y44041D01*
X137382D01*
Y43987D01*
X137220D01*
Y43933D01*
X137112D01*
Y43879D01*
X136950D01*
Y43825D01*
X136841D01*
Y43771D01*
X136679D01*
Y43717D01*
X136571D01*
Y43663D01*
X136409D01*
Y43609D01*
X136247D01*
Y43555D01*
X136084D01*
Y43501D01*
X135922D01*
Y43447D01*
X135760D01*
Y43393D01*
X135598D01*
Y43339D01*
X135436D01*
Y43284D01*
X135274D01*
Y43230D01*
X135057D01*
Y43176D01*
X134895D01*
Y43122D01*
X134679D01*
Y43068D01*
X134463D01*
Y43014D01*
X134246D01*
Y42960D01*
X134030D01*
Y42906D01*
X133760D01*
Y42852D01*
X133490D01*
Y42798D01*
X133219D01*
Y42744D01*
X132895D01*
Y42690D01*
X132571D01*
Y42636D01*
X132246D01*
Y42582D01*
X131760D01*
Y42528D01*
X131165D01*
Y42474D01*
X130300D01*
Y42419D01*
X130246D01*
Y42474D01*
X130192D01*
Y42419D01*
X128840D01*
Y42474D01*
X127867D01*
Y42528D01*
X127272D01*
Y42582D01*
X126840D01*
Y42636D01*
X126462D01*
Y42690D01*
X126137D01*
Y42744D01*
X125759D01*
Y42798D01*
X125542D01*
Y42852D01*
X125272D01*
Y42906D01*
X125002D01*
Y42960D01*
X124785D01*
Y43014D01*
X124569D01*
Y43068D01*
X124353D01*
Y43122D01*
X124137D01*
Y43176D01*
X123975D01*
Y43230D01*
X123758D01*
Y43284D01*
X123596D01*
Y43339D01*
X123434D01*
Y43393D01*
X123272D01*
Y43447D01*
X123056D01*
Y43501D01*
X122947D01*
Y43555D01*
X122785D01*
Y43609D01*
X122623D01*
Y43663D01*
X122461D01*
Y43717D01*
X122353D01*
Y43771D01*
X122191D01*
Y43825D01*
X122028D01*
Y43879D01*
X121920D01*
Y43933D01*
X121758D01*
Y43987D01*
X121650D01*
Y44041D01*
X121542D01*
Y44095D01*
X121380D01*
Y44150D01*
X121272D01*
Y44204D01*
X121163D01*
Y44258D01*
X121055D01*
Y44312D01*
X120947D01*
Y44366D01*
X120839D01*
Y44420D01*
X120677D01*
Y44474D01*
X120569D01*
Y44528D01*
X120461D01*
Y44582D01*
X120352D01*
Y44636D01*
X120244D01*
Y44690D01*
X120190D01*
Y44744D01*
X120082D01*
Y44798D01*
X119974D01*
Y44852D01*
X119866D01*
Y44906D01*
X119758D01*
Y44960D01*
X119650D01*
Y45015D01*
X119542D01*
Y45068D01*
X119488D01*
Y45123D01*
X119379D01*
Y45177D01*
X119271D01*
Y45231D01*
X119217D01*
Y45285D01*
X119109D01*
Y45339D01*
X119001D01*
Y45393D01*
X118947D01*
Y45447D01*
X118839D01*
Y45501D01*
X118731D01*
Y45555D01*
X118676D01*
Y45609D01*
X118568D01*
Y45663D01*
X118514D01*
Y45717D01*
X118406D01*
Y45771D01*
X118352D01*
Y45825D01*
X118244D01*
Y45880D01*
X118190D01*
Y45933D01*
X118082D01*
Y45988D01*
X118028D01*
Y46042D01*
X117920D01*
Y46096D01*
X117866D01*
Y46150D01*
X117757D01*
Y46204D01*
X117703D01*
Y46258D01*
X117649D01*
Y46312D01*
X117541D01*
Y46366D01*
X117487D01*
Y46420D01*
X117433D01*
Y46474D01*
X117325D01*
Y46528D01*
X117271D01*
Y46582D01*
X117217D01*
Y46636D01*
X117109D01*
Y46690D01*
X117055D01*
Y46744D01*
X117001D01*
Y46799D01*
X116946D01*
Y46853D01*
X116838D01*
Y46907D01*
X116784D01*
Y46961D01*
X116730D01*
Y47015D01*
X116676D01*
Y47069D01*
X116568D01*
Y47123D01*
X116514D01*
Y47177D01*
X116460D01*
Y47231D01*
X116406D01*
Y47285D01*
X116352D01*
Y47339D01*
X116244D01*
Y47393D01*
X116190D01*
Y47447D01*
X116136D01*
Y47501D01*
X116082D01*
Y47555D01*
X116027D01*
Y47609D01*
X115973D01*
Y47664D01*
X115919D01*
Y47718D01*
X115865D01*
Y47772D01*
X115811D01*
Y47826D01*
X115703D01*
Y47880D01*
X115649D01*
Y47934D01*
X115595D01*
Y47988D01*
X115541D01*
Y48042D01*
X115487D01*
Y48096D01*
X115433D01*
Y48150D01*
X115379D01*
Y48204D01*
X115325D01*
Y48258D01*
X115271D01*
Y48312D01*
X115217D01*
Y48366D01*
X115163D01*
Y48420D01*
X115108D01*
Y48474D01*
X115054D01*
Y48529D01*
X115000D01*
Y48583D01*
X114946D01*
Y48637D01*
X114892D01*
Y48691D01*
X114838D01*
Y48745D01*
X114784D01*
Y48799D01*
X114730D01*
Y48853D01*
X114676D01*
Y48907D01*
X114622D01*
Y48961D01*
Y49015D01*
X114568D01*
Y49069D01*
X114514D01*
Y49123D01*
X114460D01*
Y49177D01*
X114406D01*
Y49231D01*
X114352D01*
Y49285D01*
X114297D01*
Y49339D01*
X114243D01*
Y49393D01*
X114189D01*
Y49448D01*
Y49502D01*
X114135D01*
Y49556D01*
X114081D01*
Y49610D01*
X113216D01*
Y49556D01*
X113270D01*
Y49502D01*
X113324D01*
Y49448D01*
X113378D01*
Y49393D01*
Y49339D01*
X113433D01*
Y49285D01*
X113487D01*
Y49231D01*
X113541D01*
Y49177D01*
X113595D01*
Y49123D01*
X113649D01*
Y49069D01*
Y49015D01*
X113703D01*
Y48961D01*
X113757D01*
Y48907D01*
X113811D01*
Y48853D01*
X113865D01*
Y48799D01*
X113919D01*
Y48745D01*
X113973D01*
Y48691D01*
X114027D01*
Y48637D01*
X114081D01*
Y48583D01*
Y48529D01*
X114135D01*
Y48474D01*
X114189D01*
Y48420D01*
X114243D01*
Y48366D01*
X114297D01*
Y48312D01*
X114352D01*
Y48258D01*
X114406D01*
Y48204D01*
X114460D01*
Y48150D01*
X114514D01*
Y48096D01*
X114568D01*
Y48042D01*
X114622D01*
Y47988D01*
X114676D01*
Y47934D01*
X114730D01*
Y47880D01*
X114784D01*
Y47826D01*
X114838D01*
Y47772D01*
X114892D01*
Y47718D01*
X114946D01*
Y47664D01*
X115000D01*
Y47609D01*
X115054D01*
Y47555D01*
X115108D01*
Y47501D01*
X115163D01*
Y47447D01*
X115217D01*
Y47393D01*
X115271D01*
Y47339D01*
X115325D01*
Y47285D01*
X115379D01*
Y47231D01*
X115487D01*
Y47177D01*
X115541D01*
Y47123D01*
X115595D01*
Y47069D01*
X115649D01*
Y47015D01*
X115703D01*
Y46961D01*
X115757D01*
Y46907D01*
X115811D01*
Y46853D01*
X115865D01*
Y46799D01*
X115973D01*
Y46744D01*
X116027D01*
Y46690D01*
X116082D01*
Y46636D01*
X116136D01*
Y46582D01*
X116190D01*
Y46528D01*
X116298D01*
Y46474D01*
X116352D01*
Y46420D01*
X116406D01*
Y46366D01*
X116460D01*
Y46312D01*
X116568D01*
Y46258D01*
X116622D01*
Y46204D01*
X116676D01*
Y46150D01*
X116730D01*
Y46096D01*
X116838D01*
Y46042D01*
X116893D01*
Y45988D01*
X116946D01*
Y45933D01*
X117055D01*
Y45880D01*
X117109D01*
Y45825D01*
X117163D01*
Y45771D01*
X117271D01*
Y45717D01*
X117325D01*
Y45663D01*
X117433D01*
Y45609D01*
X117487D01*
Y45555D01*
X117541D01*
Y45501D01*
X117649D01*
Y45447D01*
X117703D01*
Y45393D01*
X117812D01*
Y45339D01*
X117866D01*
Y45285D01*
X117974D01*
Y45231D01*
X118028D01*
Y45177D01*
X118136D01*
Y45123D01*
X118190D01*
Y45068D01*
X118298D01*
Y45015D01*
X118352D01*
Y44960D01*
X118460D01*
Y44906D01*
X118568D01*
Y44852D01*
X118623D01*
Y44798D01*
X118731D01*
Y44744D01*
X118839D01*
Y44690D01*
X118893D01*
Y44636D01*
X119001D01*
Y44582D01*
X119109D01*
Y44528D01*
X119163D01*
Y44474D01*
X119271D01*
Y44420D01*
X119379D01*
Y44366D01*
X119488D01*
Y44312D01*
X119596D01*
Y44258D01*
X119650D01*
Y44204D01*
X119758D01*
Y44150D01*
X119866D01*
Y44095D01*
X119974D01*
Y44041D01*
X120082D01*
Y43987D01*
X120190D01*
Y43933D01*
X120298D01*
Y43879D01*
X120406D01*
Y43825D01*
X120515D01*
Y43771D01*
X120623D01*
Y43717D01*
X120785D01*
Y43663D01*
X120893D01*
Y43609D01*
X121001D01*
Y43555D01*
X121109D01*
Y43501D01*
X121272D01*
Y43447D01*
X121380D01*
Y43393D01*
X121488D01*
Y43339D01*
X121650D01*
Y43284D01*
X121758D01*
Y43230D01*
X121920D01*
Y43176D01*
X122028D01*
Y43122D01*
X122191D01*
Y43068D01*
X122353D01*
Y43014D01*
X122515D01*
Y42960D01*
X122623D01*
Y42906D01*
X122785D01*
Y42852D01*
X122947D01*
Y42798D01*
X123110D01*
Y42744D01*
X123326D01*
Y42690D01*
X123488D01*
Y42636D01*
X123650D01*
Y42582D01*
X123866D01*
Y42528D01*
X124029D01*
Y42474D01*
X124245D01*
Y42419D01*
X124461D01*
Y42365D01*
X124677D01*
Y42311D01*
X124894D01*
Y42257D01*
X125164D01*
Y42203D01*
X125434D01*
Y42149D01*
X125705D01*
Y42095D01*
X126029D01*
Y42041D01*
X126407D01*
Y41987D01*
X126732D01*
Y41933D01*
X127164D01*
Y41879D01*
X127705D01*
Y41825D01*
X128516D01*
Y41771D01*
X130516D01*
Y41825D01*
X131327D01*
Y41879D01*
X131814D01*
Y41933D01*
X132246D01*
Y41987D01*
X132679D01*
Y42041D01*
X133003D01*
Y42095D01*
X133327D01*
Y42149D01*
X133598D01*
Y42203D01*
X133868D01*
Y42257D01*
X134138D01*
Y42311D01*
X134354D01*
Y42365D01*
X134571D01*
Y42419D01*
X134787D01*
Y42474D01*
X135003D01*
Y42528D01*
X135165D01*
Y42582D01*
X135382D01*
Y42636D01*
X135544D01*
Y42690D01*
X135706D01*
Y42744D01*
X135922D01*
Y42798D01*
X136084D01*
Y42852D01*
X136247D01*
Y42906D01*
X136355D01*
Y42960D01*
X136517D01*
Y43014D01*
X136679D01*
Y43068D01*
X136841D01*
Y43122D01*
X136950D01*
Y43176D01*
X137112D01*
Y43230D01*
X137274D01*
Y43284D01*
X137382D01*
Y43339D01*
X137544D01*
Y43393D01*
X137652D01*
Y43447D01*
X137760D01*
Y43501D01*
X137923D01*
Y43555D01*
X138031D01*
Y43609D01*
X138139D01*
Y43663D01*
X138247D01*
Y43717D01*
X138355D01*
Y43771D01*
X138517D01*
Y43825D01*
X138625D01*
Y43879D01*
X138680D01*
Y43933D01*
X138788D01*
Y43987D01*
X138950D01*
Y44041D01*
X139058D01*
Y44095D01*
X139112D01*
Y44150D01*
X139274D01*
Y44204D01*
X139328D01*
Y44258D01*
X139436D01*
Y44312D01*
X139544D01*
Y44366D01*
X139653D01*
Y44420D01*
X139761D01*
Y44474D01*
X139815D01*
Y44528D01*
X139923D01*
Y44582D01*
X140031D01*
Y44636D01*
X140139D01*
Y44690D01*
X140193D01*
Y44744D01*
X140301D01*
Y44798D01*
X140410D01*
Y44852D01*
X140463D01*
Y44906D01*
X140572D01*
Y44960D01*
X140626D01*
Y45015D01*
X140734D01*
Y45068D01*
X140842D01*
Y45123D01*
X140896D01*
Y45177D01*
X141004D01*
Y45231D01*
X141058D01*
Y45285D01*
X141166D01*
Y45339D01*
X141220D01*
Y45393D01*
X141329D01*
Y45447D01*
X141383D01*
Y45501D01*
X141491D01*
Y45555D01*
X141545D01*
Y45609D01*
X141599D01*
Y45663D01*
X141707D01*
Y45717D01*
X141761D01*
Y45771D01*
X141815D01*
Y45825D01*
X141923D01*
Y45880D01*
X141977D01*
Y45933D01*
X142085D01*
Y45988D01*
X142139D01*
Y46042D01*
X142193D01*
Y46096D01*
X142248D01*
Y46150D01*
X142356D01*
Y46204D01*
X142410D01*
Y46258D01*
X142464D01*
Y46312D01*
X142572D01*
Y46366D01*
X142626D01*
Y46420D01*
X142680D01*
Y46474D01*
X142734D01*
Y46528D01*
X142788D01*
Y46582D01*
X142896D01*
Y46636D01*
X142950D01*
Y46690D01*
X143004D01*
Y46744D01*
X143059D01*
Y46799D01*
X143113D01*
Y46853D01*
X143221D01*
Y46907D01*
X143275D01*
Y46961D01*
X143329D01*
Y47015D01*
X143383D01*
Y47069D01*
X143437D01*
Y47123D01*
X143491D01*
Y47177D01*
X143545D01*
Y47231D01*
X143599D01*
Y47285D01*
X143653D01*
Y47339D01*
X143761D01*
Y47393D01*
X143815D01*
Y47447D01*
X143869D01*
Y47501D01*
X143923D01*
Y47555D01*
X143977D01*
Y47609D01*
X144032D01*
Y47664D01*
X144086D01*
Y47718D01*
X144140D01*
Y47772D01*
X144194D01*
Y47826D01*
X144248D01*
Y47880D01*
X144302D01*
Y47934D01*
X144356D01*
Y47988D01*
X144410D01*
Y48042D01*
X144464D01*
Y48096D01*
X144518D01*
Y48150D01*
X144572D01*
Y48204D01*
X144626D01*
Y48258D01*
X144680D01*
Y48312D01*
X144734D01*
Y48366D01*
X144789D01*
Y48420D01*
X144843D01*
Y48474D01*
X144897D01*
Y48529D01*
Y48583D01*
X144951D01*
Y48637D01*
X145005D01*
Y48691D01*
X145059D01*
Y48745D01*
X145113D01*
Y48799D01*
X145167D01*
Y48853D01*
X145221D01*
Y48907D01*
X145275D01*
Y48961D01*
X145329D01*
Y49015D01*
Y49069D01*
X145383D01*
Y49123D01*
X145437D01*
Y49177D01*
X145491D01*
Y49231D01*
X145545D01*
Y49285D01*
X145599D01*
Y49339D01*
Y49393D01*
X145653D01*
Y49448D01*
X145707D01*
Y49502D01*
X145762D01*
Y49556D01*
X145816D01*
Y49610D01*
X145870D01*
Y49664D01*
Y49718D01*
X145924D01*
Y49772D01*
X145978D01*
Y49826D01*
X146032D01*
Y49880D01*
Y49934D01*
X146086D01*
Y49988D01*
X146140D01*
Y50042D01*
X146194D01*
Y50096D01*
X146248D01*
Y50150D01*
Y50204D01*
X146302D01*
Y50258D01*
X146356D01*
Y50313D01*
X146410D01*
Y50367D01*
Y50421D01*
X146464D01*
Y50475D01*
X146519D01*
Y50529D01*
Y50583D01*
X146572D01*
Y50637D01*
X146627D01*
Y50691D01*
X146681D01*
Y50745D01*
Y50799D01*
X146735D01*
Y50853D01*
X146789D01*
Y50907D01*
Y50961D01*
X146843D01*
Y51015D01*
X146897D01*
Y51069D01*
Y51123D01*
X146951D01*
Y51178D01*
X147005D01*
Y51232D01*
Y51286D01*
X147059D01*
Y51340D01*
X147113D01*
Y51394D01*
Y51448D01*
X147167D01*
Y51502D01*
X147221D01*
Y51556D01*
Y51610D01*
X147275D01*
Y51664D01*
Y51718D01*
X147329D01*
Y51772D01*
X147383D01*
Y51826D01*
Y51880D01*
X147438D01*
Y51934D01*
Y51989D01*
X147492D01*
Y52043D01*
X147546D01*
Y52097D01*
Y52151D01*
X147600D01*
Y52205D01*
Y52259D01*
X147654D01*
Y52313D01*
X147708D01*
Y52367D01*
Y52421D01*
X147762D01*
Y52475D01*
Y52529D01*
X147816D01*
Y52583D01*
Y52637D01*
X147870D01*
Y52691D01*
Y52745D01*
X147924D01*
Y52799D01*
X147978D01*
Y52854D01*
Y52908D01*
X148032D01*
Y52962D01*
Y53016D01*
X148086D01*
Y53070D01*
Y53124D01*
X148140D01*
Y53178D01*
Y53232D01*
X148194D01*
Y53286D01*
Y53340D01*
X148249D01*
Y53394D01*
Y53448D01*
X148302D01*
Y53502D01*
Y53556D01*
X148357D01*
Y53610D01*
Y53664D01*
X148411D01*
Y53719D01*
Y53772D01*
X148465D01*
Y53827D01*
Y53881D01*
Y53935D01*
X148519D01*
Y53989D01*
Y54043D01*
X148573D01*
Y54097D01*
Y54151D01*
X148627D01*
Y54205D01*
Y54259D01*
X148681D01*
Y54313D01*
Y54367D01*
Y54421D01*
X148735D01*
Y54475D01*
Y54529D01*
X148789D01*
Y54584D01*
Y54637D01*
X148843D01*
Y54692D01*
Y54746D01*
Y54800D01*
X148897D01*
Y54854D01*
Y54908D01*
X148951D01*
Y54962D01*
Y55016D01*
Y55070D01*
X149005D01*
Y55124D01*
Y55178D01*
X149059D01*
Y55232D01*
Y55286D01*
Y55340D01*
X149113D01*
Y55394D01*
Y55449D01*
Y55502D01*
X149168D01*
Y55557D01*
Y55611D01*
X149222D01*
Y55665D01*
Y55719D01*
Y55773D01*
X149276D01*
Y55827D01*
Y55881D01*
Y55935D01*
X149330D01*
Y55989D01*
Y56043D01*
Y56097D01*
X149384D01*
Y56151D01*
Y56205D01*
Y56259D01*
X149438D01*
Y56313D01*
Y56367D01*
Y56422D01*
X149492D01*
Y56476D01*
Y56530D01*
Y56584D01*
Y56638D01*
X149546D01*
Y56692D01*
Y56746D01*
Y56800D01*
X149600D01*
Y56854D01*
Y56908D01*
Y56962D01*
Y57016D01*
X149654D01*
Y57070D01*
Y57124D01*
Y57178D01*
X149708D01*
Y57232D01*
Y57287D01*
Y57341D01*
Y57395D01*
X149762D01*
Y57449D01*
Y57503D01*
Y57557D01*
Y57611D01*
X149816D01*
Y57665D01*
Y57719D01*
Y57773D01*
Y57827D01*
X149870D01*
Y57881D01*
Y57935D01*
Y57989D01*
Y58043D01*
X149924D01*
Y58097D01*
Y58152D01*
Y58206D01*
Y58260D01*
Y58314D01*
X149978D01*
Y58368D01*
Y58422D01*
Y58476D01*
Y58530D01*
Y58584D01*
X150032D01*
Y58638D01*
Y58692D01*
Y58746D01*
Y58800D01*
Y58854D01*
X150087D01*
Y58908D01*
Y58963D01*
Y59017D01*
Y59071D01*
Y59125D01*
X150141D01*
Y59179D01*
Y59233D01*
Y59287D01*
Y59341D01*
Y59395D01*
Y59449D01*
X150195D01*
Y59503D01*
Y59557D01*
Y59611D01*
Y59665D01*
Y59719D01*
Y59773D01*
Y59828D01*
X150249D01*
Y59882D01*
Y59936D01*
Y59990D01*
Y60044D01*
Y60098D01*
Y60152D01*
Y60206D01*
Y60260D01*
X150303D01*
Y60314D01*
Y60368D01*
Y60422D01*
Y60476D01*
Y60530D01*
Y60584D01*
Y60638D01*
Y60693D01*
Y60747D01*
Y60801D01*
X150357D01*
Y60855D01*
Y60909D01*
Y60963D01*
Y61017D01*
Y61071D01*
Y61125D01*
Y61179D01*
Y61233D01*
Y61287D01*
Y61341D01*
Y61395D01*
Y61449D01*
Y61503D01*
Y61557D01*
X150411D01*
Y61611D01*
Y61666D01*
Y61720D01*
X150357D01*
Y61774D01*
X150411D01*
Y61828D01*
Y61882D01*
Y61936D01*
Y61990D01*
Y62044D01*
Y62098D01*
Y62152D01*
Y62206D01*
Y62260D01*
Y62314D01*
Y62368D01*
Y62423D01*
D02*
G37*
%LPD*%
G36*
X142455Y68811D02*
Y68757D01*
Y68703D01*
Y68649D01*
Y68595D01*
Y68541D01*
Y68487D01*
Y68433D01*
Y68379D01*
Y68325D01*
Y68270D01*
Y68216D01*
Y68162D01*
Y68108D01*
Y68054D01*
Y68000D01*
Y67946D01*
Y67892D01*
Y67838D01*
Y67784D01*
Y67730D01*
Y67676D01*
Y67622D01*
Y67568D01*
Y67514D01*
Y67459D01*
Y67405D01*
Y67351D01*
Y67297D01*
Y67243D01*
Y67189D01*
Y67135D01*
Y67081D01*
Y67027D01*
Y66973D01*
Y66919D01*
Y66865D01*
Y66811D01*
Y66757D01*
Y66703D01*
Y66649D01*
Y66594D01*
Y66540D01*
Y66486D01*
Y66432D01*
Y66378D01*
Y66324D01*
Y66270D01*
Y66216D01*
Y66162D01*
Y66108D01*
Y66054D01*
Y66000D01*
X138400D01*
Y66054D01*
Y66108D01*
Y66162D01*
Y66216D01*
Y66270D01*
Y66324D01*
Y66378D01*
Y66432D01*
Y66486D01*
Y66540D01*
Y66594D01*
Y66649D01*
Y66703D01*
Y66757D01*
Y66811D01*
Y66865D01*
Y66919D01*
Y66973D01*
Y67027D01*
Y67081D01*
Y67135D01*
Y67189D01*
Y67243D01*
Y67297D01*
Y67351D01*
Y67405D01*
Y67459D01*
Y67514D01*
Y67568D01*
Y67622D01*
Y67676D01*
Y67730D01*
Y67784D01*
Y67838D01*
Y67892D01*
Y67946D01*
Y68000D01*
Y68054D01*
Y68108D01*
Y68162D01*
Y68216D01*
Y68270D01*
Y68325D01*
Y68379D01*
Y68433D01*
Y68487D01*
Y68541D01*
Y68595D01*
Y68649D01*
Y68703D01*
Y68757D01*
Y68811D01*
Y68865D01*
X142455D01*
Y68811D01*
D02*
G37*
G36*
X153946Y72082D02*
Y72028D01*
Y71974D01*
Y71920D01*
Y71865D01*
Y71811D01*
Y71757D01*
Y71703D01*
Y71649D01*
Y71595D01*
Y71541D01*
Y71487D01*
Y71433D01*
Y71379D01*
Y71325D01*
Y71271D01*
Y71217D01*
Y71163D01*
Y71109D01*
Y71055D01*
Y71000D01*
Y70946D01*
Y70892D01*
Y70838D01*
Y70784D01*
Y70730D01*
Y70676D01*
Y70622D01*
Y70568D01*
Y70514D01*
Y70460D01*
Y70406D01*
Y70352D01*
Y70298D01*
Y70244D01*
Y70189D01*
Y70135D01*
Y70081D01*
Y70027D01*
Y69973D01*
Y69919D01*
Y69865D01*
Y69811D01*
Y69757D01*
Y69703D01*
Y69649D01*
Y69595D01*
Y69541D01*
Y69487D01*
Y69433D01*
Y69379D01*
Y69324D01*
Y69270D01*
Y69216D01*
Y69162D01*
Y69108D01*
Y69054D01*
Y69000D01*
Y68946D01*
Y68892D01*
Y68838D01*
Y68784D01*
Y68730D01*
Y68676D01*
Y68622D01*
Y68568D01*
Y68514D01*
Y68459D01*
Y68405D01*
Y68351D01*
Y68297D01*
Y68243D01*
Y68189D01*
Y68135D01*
Y68081D01*
Y68027D01*
Y67973D01*
Y67919D01*
Y67865D01*
Y67811D01*
Y67757D01*
Y67703D01*
Y67649D01*
Y67594D01*
Y67541D01*
Y67486D01*
Y67432D01*
Y67378D01*
Y67324D01*
Y67270D01*
Y67216D01*
Y67162D01*
Y67108D01*
Y67054D01*
Y67000D01*
Y66946D01*
Y66892D01*
Y66838D01*
Y66784D01*
Y66729D01*
Y66676D01*
Y66621D01*
Y66567D01*
Y66513D01*
Y66459D01*
Y66405D01*
Y66351D01*
Y66297D01*
Y66243D01*
Y66189D01*
Y66135D01*
X153838D01*
Y66081D01*
X153784D01*
Y66135D01*
X153676D01*
Y66081D01*
X153622D01*
Y66135D01*
X150108D01*
Y66081D01*
X150054D01*
Y66135D01*
X150000D01*
Y66189D01*
Y66243D01*
Y66297D01*
Y66351D01*
Y66405D01*
Y66459D01*
Y66513D01*
Y66567D01*
Y66621D01*
Y66676D01*
Y66729D01*
Y66784D01*
Y66838D01*
Y66892D01*
Y66946D01*
Y67000D01*
Y67054D01*
Y67108D01*
Y67162D01*
Y67216D01*
Y67270D01*
Y67324D01*
Y67378D01*
Y67432D01*
Y67486D01*
Y67541D01*
Y67594D01*
Y67649D01*
Y67703D01*
Y67757D01*
Y67811D01*
Y67865D01*
Y67919D01*
Y67973D01*
Y68027D01*
Y68081D01*
Y68135D01*
Y68189D01*
Y68243D01*
Y68297D01*
Y68351D01*
Y68405D01*
Y68459D01*
Y68514D01*
Y68568D01*
Y68622D01*
Y68676D01*
Y68730D01*
Y68784D01*
Y68838D01*
Y68892D01*
Y68946D01*
Y69000D01*
Y69054D01*
Y69108D01*
Y69162D01*
Y69216D01*
Y69270D01*
Y69324D01*
Y69379D01*
Y69433D01*
Y69487D01*
Y69541D01*
Y69595D01*
Y69649D01*
Y69703D01*
Y69757D01*
Y69811D01*
Y69865D01*
Y69919D01*
Y69973D01*
Y70027D01*
Y70081D01*
Y70135D01*
Y70189D01*
Y70244D01*
Y70298D01*
Y70352D01*
Y70406D01*
Y70460D01*
Y70514D01*
Y70568D01*
Y70622D01*
Y70676D01*
Y70730D01*
Y70784D01*
Y70838D01*
Y70892D01*
Y70946D01*
Y71000D01*
Y71055D01*
Y71109D01*
Y71163D01*
Y71217D01*
Y71271D01*
Y71325D01*
Y71379D01*
Y71433D01*
Y71487D01*
Y71541D01*
Y71595D01*
Y71649D01*
Y71703D01*
Y71757D01*
Y71811D01*
Y71865D01*
Y71920D01*
Y71974D01*
Y72028D01*
Y72082D01*
Y72136D01*
X153946D01*
Y72082D01*
D02*
G37*
D56*
X21785Y62879D02*
X20643Y59879D01*
X19500Y62879D01*
X19929Y61879D02*
X21357D01*
X22485Y60879D02*
Y62879D01*
Y61736D02*
X22628Y61308D01*
X22914Y61022D01*
X23199Y60879D01*
X23628D01*
X23899D02*
Y62879D01*
Y61451D02*
X24328Y61022D01*
X24613Y60879D01*
X25042D01*
X25327Y61022D01*
X25470Y61451D01*
Y62879D01*
Y61451D02*
X25899Y61022D01*
X26184Y60879D01*
X26613D01*
X26898Y61022D01*
X27041Y61451D01*
Y62879D01*
X29698Y60879D02*
Y62879D01*
Y61308D02*
X29412Y61022D01*
X29127Y60879D01*
X28698D01*
X28412Y61022D01*
X28127Y61308D01*
X27984Y61736D01*
Y62022D01*
X28127Y62450D01*
X28412Y62736D01*
X28698Y62879D01*
X29127D01*
X29412Y62736D01*
X29698Y62450D01*
X30498Y60879D02*
Y62879D01*
Y61451D02*
X30926Y61022D01*
X31212Y60879D01*
X31640D01*
X31926Y61022D01*
X32069Y61451D01*
Y62879D01*
X34568Y59879D02*
Y62879D01*
Y61308D02*
X34282Y61022D01*
X33997Y60879D01*
X33568D01*
X33283Y61022D01*
X32997Y61308D01*
X32854Y61736D01*
Y62022D01*
X32997Y62450D01*
X33283Y62736D01*
X33568Y62879D01*
X33997D01*
X34282Y62736D01*
X34568Y62450D01*
X36082Y60879D02*
X35796Y61022D01*
X35511Y61308D01*
X35368Y61736D01*
Y62022D01*
X35511Y62450D01*
X35796Y62736D01*
X36082Y62879D01*
X36511D01*
X36796Y62736D01*
X37082Y62450D01*
X37225Y62022D01*
Y61736D01*
X37082Y61308D01*
X36796Y61022D01*
X36511Y60879D01*
X36082D01*
X40238Y61451D02*
X41524D01*
X41952Y61308D01*
X42095Y61165D01*
X42238Y60879D01*
Y60451D01*
X42095Y60165D01*
X41952Y60022D01*
X41524Y59879D01*
X40238D01*
Y62879D01*
X43195Y59879D02*
X43338Y60022D01*
X43481Y59879D01*
X43338Y59737D01*
X43195Y59879D01*
X43338Y60879D02*
Y62879D01*
X44009Y60879D02*
Y62879D01*
Y61451D02*
X44438Y61022D01*
X44723Y60879D01*
X45152D01*
X45437Y61022D01*
X45580Y61451D01*
Y62879D01*
X48080Y60879D02*
Y62879D01*
Y61308D02*
X47794Y61022D01*
X47508Y60879D01*
X47080D01*
X46794Y61022D01*
X46508Y61308D01*
X46366Y61736D01*
Y62022D01*
X46508Y62450D01*
X46794Y62736D01*
X47080Y62879D01*
X47508D01*
X47794Y62736D01*
X48080Y62450D01*
X48879Y59879D02*
Y62879D01*
X49508Y61736D02*
X51222D01*
Y61451D01*
X51079Y61165D01*
X50936Y61022D01*
X50651Y60879D01*
X50222D01*
X49936Y61022D01*
X49651Y61308D01*
X49508Y61736D01*
Y62022D01*
X49651Y62450D01*
X49936Y62736D01*
X50222Y62879D01*
X50651D01*
X50936Y62736D01*
X51222Y62450D01*
X53436Y61308D02*
X53293Y61022D01*
X52864Y60879D01*
X52436D01*
X52007Y61022D01*
X51864Y61308D01*
X52007Y61594D01*
X52293Y61736D01*
X53007Y61879D01*
X53293Y62022D01*
X53436Y62308D01*
Y62450D01*
X53293Y62736D01*
X52864Y62879D01*
X52436D01*
X52007Y62736D01*
X51864Y62450D01*
X20928Y65062D02*
Y67347D01*
X20785Y67775D01*
X20643Y67918D01*
X20357Y68061D01*
X20071D01*
X19786Y67918D01*
X19643Y67775D01*
X19500Y67347D01*
Y67061D01*
X21700Y66061D02*
Y67490D01*
X21842Y67918D01*
X22128Y68061D01*
X22557D01*
X22842Y67918D01*
X23271Y67490D01*
Y66061D02*
Y68061D01*
X24056Y65062D02*
Y68061D01*
X24970Y65062D02*
X25113Y65204D01*
X25256Y65062D01*
X25113Y64919D01*
X24970Y65062D01*
X25113Y66061D02*
Y68061D01*
X27498Y66061D02*
Y68061D01*
Y66490D02*
X27213Y66204D01*
X26927Y66061D01*
X26498D01*
X26213Y66204D01*
X25927Y66490D01*
X25784Y66918D01*
Y67204D01*
X25927Y67633D01*
X26213Y67918D01*
X26498Y68061D01*
X26927D01*
X27213Y67918D01*
X27498Y67633D01*
X28298Y66061D02*
Y68061D01*
Y66633D02*
X28727Y66204D01*
X29012Y66061D01*
X29441D01*
X29726Y66204D01*
X29869Y66633D01*
Y68061D01*
X35011Y65490D02*
X34725Y65204D01*
X34297Y65062D01*
X33726D01*
X33297Y65204D01*
X33011Y65490D01*
Y65776D01*
X33154Y66061D01*
X33297Y66204D01*
X33583Y66347D01*
X34440Y66633D01*
X34725Y66776D01*
X34868Y66918D01*
X35011Y67204D01*
Y67633D01*
X34725Y67918D01*
X34297Y68061D01*
X33726D01*
X33297Y67918D01*
X33011Y67633D01*
X36111Y65062D02*
Y67490D01*
X36254Y67918D01*
X36539Y68061D01*
X36825D01*
X35682Y66061D02*
X36682D01*
X37396Y67775D02*
X37253Y67918D01*
X37396Y68061D01*
X37539Y67918D01*
X37396Y67775D01*
X41981Y65062D02*
Y67347D01*
X41838Y67775D01*
X41695Y67918D01*
X41410Y68061D01*
X41124D01*
X40838Y67918D01*
X40696Y67775D01*
X40553Y67347D01*
Y67061D01*
X44466Y66061D02*
Y68061D01*
Y66490D02*
X44181Y66204D01*
X43895Y66061D01*
X43466D01*
X43181Y66204D01*
X42895Y66490D01*
X42752Y66918D01*
Y67204D01*
X42895Y67633D01*
X43181Y67918D01*
X43466Y68061D01*
X43895D01*
X44181Y67918D01*
X44466Y67633D01*
X45266Y66061D02*
Y68061D01*
Y66633D02*
X45694Y66204D01*
X45980Y66061D01*
X46409D01*
X46694Y66204D01*
X46837Y66633D01*
Y68061D01*
Y66633D02*
X47265Y66204D01*
X47551Y66061D01*
X47980D01*
X48265Y66204D01*
X48408Y66633D01*
Y68061D01*
X49351Y66918D02*
X51065D01*
Y66633D01*
X50922Y66347D01*
X50779Y66204D01*
X50493Y66061D01*
X50065D01*
X49779Y66204D01*
X49494Y66490D01*
X49351Y66918D01*
Y67204D01*
X49494Y67633D01*
X49779Y67918D01*
X50065Y68061D01*
X50493D01*
X50779Y67918D01*
X51065Y67633D01*
X53278Y66490D02*
X53136Y66204D01*
X52707Y66061D01*
X52279D01*
X51850Y66204D01*
X51707Y66490D01*
X51850Y66776D01*
X52136Y66918D01*
X52850Y67061D01*
X53136Y67204D01*
X53278Y67490D01*
Y67633D01*
X53136Y67918D01*
X52707Y68061D01*
X52279D01*
X51850Y67918D01*
X51707Y67633D01*
X21785Y73100D02*
X20643Y70101D01*
X19500Y73100D01*
X19929Y72100D02*
X21357D01*
X22485Y70101D02*
Y73100D01*
X24827Y71101D02*
Y73100D01*
Y71529D02*
X24542Y71243D01*
X24256Y71101D01*
X23828D01*
X23542Y71243D01*
X23256Y71529D01*
X23113Y71958D01*
Y72243D01*
X23256Y72672D01*
X23542Y72957D01*
X23828Y73100D01*
X24256D01*
X24542Y72957D01*
X24827Y72672D01*
X25627Y71101D02*
Y73100D01*
Y71672D02*
X26056Y71243D01*
X26341Y71101D01*
X26770D01*
X27055Y71243D01*
X27198Y71672D01*
Y73100D01*
X30340Y70101D02*
X31483Y73100D01*
X32626Y70101D02*
X31483Y73100D01*
X34725Y71101D02*
Y73100D01*
Y71529D02*
X34440Y71243D01*
X34154Y71101D01*
X33726D01*
X33440Y71243D01*
X33154Y71529D01*
X33011Y71958D01*
Y72243D01*
X33154Y72672D01*
X33440Y72957D01*
X33726Y73100D01*
X34154D01*
X34440Y72957D01*
X34725Y72672D01*
X35525Y71101D02*
Y73100D01*
Y71672D02*
X35954Y71243D01*
X36239Y71101D01*
X36668D01*
X36953Y71243D01*
X37096Y71672D01*
Y73100D01*
X37882Y71101D02*
Y73100D01*
Y71672D02*
X38310Y71243D01*
X38596Y71101D01*
X39024D01*
X39310Y71243D01*
X39453Y71672D01*
Y73100D01*
X41952Y71101D02*
Y73100D01*
Y71529D02*
X41667Y71243D01*
X41381Y71101D01*
X40953D01*
X40667Y71243D01*
X40381Y71529D01*
X40238Y71958D01*
Y72243D01*
X40381Y72672D01*
X40667Y72957D01*
X40953Y73100D01*
X41381D01*
X41667Y72957D01*
X41952Y72672D01*
X44323Y71529D02*
X44181Y71243D01*
X43752Y71101D01*
X43323D01*
X42895Y71243D01*
X42752Y71529D01*
X42895Y71815D01*
X43181Y71958D01*
X43895Y72100D01*
X44181Y72243D01*
X44323Y72529D01*
Y72672D01*
X44181Y72957D01*
X43752Y73100D01*
X43323D01*
X42895Y72957D01*
X42752Y72672D01*
X45094Y71101D02*
X45952Y73100D01*
X46808Y71101D02*
X45952Y73100D01*
X45666Y73672D01*
X45380Y73957D01*
X45094Y74100D01*
X44952D01*
M02*
